G04 ================== begin FILE IDENTIFICATION RECORD ==================*
G04 Layout Name:  15669-1.brd*
G04 Film Name:    TSMD*
G04 File Format:  Gerber RS274X*
G04 File Origin:  Cadence Allegro 16.5-S056*
G04 Origin Date:  Wed Nov 16 04:08:22 2016*
G04 *
G04 Layer:  VIA CLASS/PASTEMASK_TOP*
G04 Layer:  PIN/PASTEMASK_TOP*
G04 Layer:  PACKAGE GEOMETRY/PASTEMASK_TOP*
G04 Layer:  DRAWING FORMAT/LAYER_PCB_STORY*
G04 Layer:  DRAWING FORMAT/LAYER_PAST_T*
G04 Layer:  BOARD GEOMETRY/PANEL_OUTLINE*
G04 *
G04 Offset:    (0.00 0.00)*
G04 Mirror:    No*
G04 Mode:      Positive*
G04 Rotation:  0*
G04 FullContactRelief:  No*
G04 UndefLineWidth:     6.00*
G04 ================== end FILE IDENTIFICATION RECORD ====================*
%FSLAX35Y35*MOIN*%
%IR0*IPPOS*OFA0.00000B0.00000*MIA0B0*SFA1.00000B1.00000*%
%AMMACRO56*
4,1,40,.013,.017,
-.013,.017,
-.013695,.016939,
-.014368,.016759,
-.015,.016464,
-.015571,.016064,
-.016064,.015571,
-.016464,.015,
-.016759,.014368,
-.016939,.013695,
-.017,.013,
-.017,-.013,
-.016939,-.013695,
-.016759,-.014368,
-.016464,-.015,
-.016064,-.015571,
-.015571,-.016064,
-.015,-.016464,
-.014368,-.016759,
-.013695,-.016939,
-.013,-.017,
.013,-.017,
.013695,-.016939,
.014368,-.016759,
.015,-.016464,
.015571,-.016064,
.016064,-.015571,
.016464,-.015,
.016759,-.014368,
.016939,-.013695,
.017,-.013,
.017,.013,
.016939,.013695,
.016759,.014368,
.016464,.015,
.016064,.015571,
.015571,.016064,
.015,.016464,
.014368,.016759,
.013695,.016939,
.013,.017,
0.0*
%
%ADD56MACRO56*%
%AMMACRO30*
4,1,40,.017,-.013,
.017,.013,
.016939,.013695,
.016759,.014368,
.016464,.015,
.016064,.015571,
.015571,.016064,
.015,.016464,
.014368,.016759,
.013695,.016939,
.013,.017,
-.013,.017,
-.013695,.016939,
-.014368,.016759,
-.015,.016464,
-.015571,.016064,
-.016064,.015571,
-.016464,.015,
-.016759,.014368,
-.016939,.013695,
-.017,.013,
-.017,-.013,
-.016939,-.013695,
-.016759,-.014368,
-.016464,-.015,
-.016064,-.015571,
-.015571,-.016064,
-.015,-.016464,
-.014368,-.016759,
-.013695,-.016939,
-.013,-.017,
.013,-.017,
.013695,-.016939,
.014368,-.016759,
.015,-.016464,
.015571,-.016064,
.016064,-.015571,
.016464,-.015,
.016759,-.014368,
.016939,-.013695,
.017,-.013,
0.0*
%
%ADD30MACRO30*%
%AMMACRO79*
4,1,3,.025,.0125,
0.0,-.0125,
-.025,.0125,
.025,.0125,
0.0*
%
%ADD79MACRO79*%
%ADD81R,.23X.032*%
%ADD29R,.11X.045*%
%ADD47R,.045X.11*%
%ADD13R,.11X.045*%
%ADD10C,.04*%
%ADD51C,.032*%
%ADD12C,.028*%
%ADD75R,.062X.062*%
%AMMACRO33*
4,1,40,.0225,-.007,
.022378,-.008389,
.022018,-.009736,
.021428,-.011,
.020628,-.012142,
.019642,-.013128,
.0185,-.013928,
.017236,-.014518,
.015889,-.014878,
.0145,-.015,
-.0145,-.015,
-.015889,-.014878,
-.017236,-.014518,
-.0185,-.013928,
-.019642,-.013128,
-.020628,-.012142,
-.021428,-.011,
-.022018,-.009736,
-.022378,-.008389,
-.0225,-.007,
-.0225,.007,
-.022378,.008389,
-.022018,.009736,
-.021428,.011,
-.020628,.012142,
-.019642,.013128,
-.0185,.013928,
-.017236,.014518,
-.015889,.014878,
-.0145,.015,
.0145,.015,
.015889,.014878,
.017236,.014518,
.0185,.013928,
.019642,.013128,
.020628,.012142,
.021428,.011,
.022018,.009736,
.022378,.008389,
.0225,.007,
.0225,-.007,
0.0*
%
%ADD33MACRO33*%
%AMMACRO34*
4,1,40,-.007,-.0225,
-.008389,-.022378,
-.009736,-.022018,
-.011,-.021428,
-.012142,-.020628,
-.013128,-.019642,
-.013928,-.0185,
-.014518,-.017236,
-.014878,-.015889,
-.015,-.0145,
-.015,.0145,
-.014878,.015889,
-.014518,.017236,
-.013928,.0185,
-.013128,.019642,
-.012142,.020628,
-.011,.021428,
-.009736,.022018,
-.008389,.022378,
-.007,.0225,
.007,.0225,
.008389,.022378,
.009736,.022018,
.011,.021428,
.012142,.020628,
.013128,.019642,
.013928,.0185,
.014518,.017236,
.014878,.015889,
.015,.0145,
.015,-.0145,
.014878,-.015889,
.014518,-.017236,
.013928,-.0185,
.013128,-.019642,
.012142,-.020628,
.011,-.021428,
.009736,-.022018,
.008389,-.022378,
.007,-.0225,
-.007,-.0225,
0.0*
%
%ADD34MACRO34*%
%AMMACRO35*
4,1,40,.007,.011,
-.007,.011,
-.007695,.010939,
-.008368,.010759,
-.009,.010464,
-.009571,.010064,
-.010064,.009571,
-.010464,.009,
-.010759,.008368,
-.010939,.007695,
-.011,.007,
-.011,-.007,
-.010939,-.007695,
-.010759,-.008368,
-.010464,-.009,
-.010064,-.009571,
-.009571,-.010064,
-.009,-.010464,
-.008368,-.010759,
-.007695,-.010939,
-.007,-.011,
.007,-.011,
.007695,-.010939,
.008368,-.010759,
.009,-.010464,
.009571,-.010064,
.010064,-.009571,
.010464,-.009,
.010759,-.008368,
.010939,-.007695,
.011,-.007,
.011,.007,
.010939,.007695,
.010759,.008368,
.010464,.009,
.010064,.009571,
.009571,.010064,
.009,.010464,
.008368,.010759,
.007695,.010939,
.007,.011,
0.0*
%
%ADD35MACRO35*%
%AMMACRO23*
4,1,40,.011,-.007,
.011,.007,
.010939,.007695,
.010759,.008368,
.010464,.009,
.010064,.009571,
.009571,.010064,
.009,.010464,
.008368,.010759,
.007695,.010939,
.007,.011,
-.007,.011,
-.007695,.010939,
-.008368,.010759,
-.009,.010464,
-.009571,.010064,
-.010064,.009571,
-.010464,.009,
-.010759,.008368,
-.010939,.007695,
-.011,.007,
-.011,-.007,
-.010939,-.007695,
-.010759,-.008368,
-.010464,-.009,
-.010064,-.009571,
-.009571,-.010064,
-.009,-.010464,
-.008368,-.010759,
-.007695,-.010939,
-.007,-.011,
.007,-.011,
.007695,-.010939,
.008368,-.010759,
.009,-.010464,
.009571,-.010064,
.010064,-.009571,
.010464,-.009,
.010759,-.008368,
.010939,-.007695,
.011,-.007,
0.0*
%
%ADD23MACRO23*%
%AMMACRO19*
4,1,40,-.012,.008,
-.012,-.008,
-.011939,-.008695,
-.011759,-.009368,
-.011464,-.01,
-.011064,-.010571,
-.010571,-.011064,
-.01,-.011464,
-.009368,-.011759,
-.008695,-.011939,
-.008,-.012,
.008,-.012,
.008695,-.011939,
.009368,-.011759,
.01,-.011464,
.010571,-.011064,
.011064,-.010571,
.011464,-.01,
.011759,-.009368,
.011939,-.008695,
.012,-.008,
.012,.008,
.011939,.008695,
.011759,.009368,
.011464,.01,
.011064,.010571,
.010571,.011064,
.01,.011464,
.009368,.011759,
.008695,.011939,
.008,.012,
-.008,.012,
-.008695,.011939,
-.009368,.011759,
-.01,.011464,
-.010571,.011064,
-.011064,.010571,
-.011464,.01,
-.011759,.009368,
-.011939,.008695,
-.012,.008,
0.0*
%
%ADD19MACRO19*%
%ADD61R,.089X.089*%
%AMMACRO41*
4,1,40,.008,.012,
-.008,.012,
-.008695,.011939,
-.009368,.011759,
-.01,.011464,
-.010571,.011064,
-.011064,.010571,
-.011464,.01,
-.011759,.009368,
-.011939,.008695,
-.012,.008,
-.012,-.008,
-.011939,-.008695,
-.011759,-.009368,
-.011464,-.01,
-.011064,-.010571,
-.010571,-.011064,
-.01,-.011464,
-.009368,-.011759,
-.008695,-.011939,
-.008,-.012,
.008,-.012,
.008695,-.011939,
.009368,-.011759,
.01,-.011464,
.010571,-.011064,
.011064,-.010571,
.011464,-.01,
.011759,-.009368,
.011939,-.008695,
.012,-.008,
.012,.008,
.011939,.008695,
.011759,.009368,
.011464,.01,
.011064,.010571,
.010571,.011064,
.01,.011464,
.009368,.011759,
.008695,.011939,
.008,.012,
0.0*
%
%ADD41MACRO41*%
%AMMACRO20*
4,1,40,-.013,-.017,
.013,-.017,
.013695,-.016939,
.014368,-.016759,
.015,-.016464,
.015571,-.016064,
.016064,-.015571,
.016464,-.015,
.016759,-.014368,
.016939,-.013695,
.017,-.013,
.017,.013,
.016939,.013695,
.016759,.014368,
.016464,.015,
.016064,.015571,
.015571,.016064,
.015,.016464,
.014368,.016759,
.013695,.016939,
.013,.017,
-.013,.017,
-.013695,.016939,
-.014368,.016759,
-.015,.016464,
-.015571,.016064,
-.016064,.015571,
-.016464,.015,
-.016759,.014368,
-.016939,.013695,
-.017,.013,
-.017,-.013,
-.016939,-.013695,
-.016759,-.014368,
-.016464,-.015,
-.016064,-.015571,
-.015571,-.016064,
-.015,-.016464,
-.014368,-.016759,
-.013695,-.016939,
-.013,-.017,
0.0*
%
%ADD20MACRO20*%
%AMMACRO42*
4,1,40,-.017,.013,
-.017,-.013,
-.016939,-.013695,
-.016759,-.014368,
-.016464,-.015,
-.016064,-.015571,
-.015571,-.016064,
-.015,-.016464,
-.014368,-.016759,
-.013695,-.016939,
-.013,-.017,
.013,-.017,
.013695,-.016939,
.014368,-.016759,
.015,-.016464,
.015571,-.016064,
.016064,-.015571,
.016464,-.015,
.016759,-.014368,
.016939,-.013695,
.017,-.013,
.017,.013,
.016939,.013695,
.016759,.014368,
.016464,.015,
.016064,.015571,
.015571,.016064,
.015,.016464,
.014368,.016759,
.013695,.016939,
.013,.017,
-.013,.017,
-.013695,.016939,
-.014368,.016759,
-.015,.016464,
-.015571,.016064,
-.016064,.015571,
-.016464,.015,
-.016759,.014368,
-.016939,.013695,
-.017,.013,
0.0*
%
%ADD42MACRO42*%
%AMMACRO36*
4,1,40,.007,.011,
-.007,.011,
-.007695,.010939,
-.008368,.010759,
-.009,.010464,
-.009571,.010064,
-.010064,.009571,
-.010464,.009,
-.010759,.008368,
-.010939,.007695,
-.011,.007,
-.011,-.007,
-.010939,-.007695,
-.010759,-.008368,
-.010464,-.009,
-.010064,-.009571,
-.009571,-.010064,
-.009,-.010464,
-.008368,-.010759,
-.007695,-.010939,
-.007,-.011,
.007,-.011,
.007695,-.010939,
.008368,-.010759,
.009,-.010464,
.009571,-.010064,
.010064,-.009571,
.010464,-.009,
.010759,-.008368,
.010939,-.007695,
.011,-.007,
.011,.007,
.010939,.007695,
.010759,.008368,
.010464,.009,
.010064,.009571,
.009571,.010064,
.009,.010464,
.008368,.010759,
.007695,.010939,
.007,.011,
0.0*
%
%ADD36MACRO36*%
%AMMACRO24*
4,1,40,.011,-.007,
.011,.007,
.010939,.007695,
.010759,.008368,
.010464,.009,
.010064,.009571,
.009571,.010064,
.009,.010464,
.008368,.010759,
.007695,.010939,
.007,.011,
-.007,.011,
-.007695,.010939,
-.008368,.010759,
-.009,.010464,
-.009571,.010064,
-.010064,.009571,
-.010464,.009,
-.010759,.008368,
-.010939,.007695,
-.011,.007,
-.011,-.007,
-.010939,-.007695,
-.010759,-.008368,
-.010464,-.009,
-.010064,-.009571,
-.009571,-.010064,
-.009,-.010464,
-.008368,-.010759,
-.007695,-.010939,
-.007,-.011,
.007,-.011,
.007695,-.010939,
.008368,-.010759,
.009,-.010464,
.009571,-.010064,
.010064,-.009571,
.010464,-.009,
.010759,-.008368,
.010939,-.007695,
.011,-.007,
0.0*
%
%ADD24MACRO24*%
%AMMACRO18*
4,1,40,-.012,.008,
-.012,-.008,
-.011939,-.008695,
-.011759,-.009368,
-.011464,-.01,
-.011064,-.010571,
-.010571,-.011064,
-.01,-.011464,
-.009368,-.011759,
-.008695,-.011939,
-.008,-.012,
.008,-.012,
.008695,-.011939,
.009368,-.011759,
.01,-.011464,
.010571,-.011064,
.011064,-.010571,
.011464,-.01,
.011759,-.009368,
.011939,-.008695,
.012,-.008,
.012,.008,
.011939,.008695,
.011759,.009368,
.011464,.01,
.011064,.010571,
.010571,.011064,
.01,.011464,
.009368,.011759,
.008695,.011939,
.008,.012,
-.008,.012,
-.008695,.011939,
-.009368,.011759,
-.01,.011464,
-.010571,.011064,
-.011064,.010571,
-.011464,.01,
-.011759,.009368,
-.011939,.008695,
-.012,.008,
0.0*
%
%ADD18MACRO18*%
%AMMACRO40*
4,1,40,.008,.012,
-.008,.012,
-.008695,.011939,
-.009368,.011759,
-.01,.011464,
-.010571,.011064,
-.011064,.010571,
-.011464,.01,
-.011759,.009368,
-.011939,.008695,
-.012,.008,
-.012,-.008,
-.011939,-.008695,
-.011759,-.009368,
-.011464,-.01,
-.011064,-.010571,
-.010571,-.011064,
-.01,-.011464,
-.009368,-.011759,
-.008695,-.011939,
-.008,-.012,
.008,-.012,
.008695,-.011939,
.009368,-.011759,
.01,-.011464,
.010571,-.011064,
.011064,-.010571,
.011464,-.01,
.011759,-.009368,
.011939,-.008695,
.012,-.008,
.012,.008,
.011939,.008695,
.011759,.009368,
.011464,.01,
.011064,.010571,
.010571,.011064,
.01,.011464,
.009368,.011759,
.008695,.011939,
.008,.012,
0.0*
%
%ADD40MACRO40*%
%AMMACRO21*
4,1,40,-.013,-.017,
.013,-.017,
.013695,-.016939,
.014368,-.016759,
.015,-.016464,
.015571,-.016064,
.016064,-.015571,
.016464,-.015,
.016759,-.014368,
.016939,-.013695,
.017,-.013,
.017,.013,
.016939,.013695,
.016759,.014368,
.016464,.015,
.016064,.015571,
.015571,.016064,
.015,.016464,
.014368,.016759,
.013695,.016939,
.013,.017,
-.013,.017,
-.013695,.016939,
-.014368,.016759,
-.015,.016464,
-.015571,.016064,
-.016064,.015571,
-.016464,.015,
-.016759,.014368,
-.016939,.013695,
-.017,.013,
-.017,-.013,
-.016939,-.013695,
-.016759,-.014368,
-.016464,-.015,
-.016064,-.015571,
-.015571,-.016064,
-.015,-.016464,
-.014368,-.016759,
-.013695,-.016939,
-.013,-.017,
0.0*
%
%ADD21MACRO21*%
%AMMACRO50*
4,1,40,-.017,.013,
-.017,-.013,
-.016939,-.013695,
-.016759,-.014368,
-.016464,-.015,
-.016064,-.015571,
-.015571,-.016064,
-.015,-.016464,
-.014368,-.016759,
-.013695,-.016939,
-.013,-.017,
.013,-.017,
.013695,-.016939,
.014368,-.016759,
.015,-.016464,
.015571,-.016064,
.016064,-.015571,
.016464,-.015,
.016759,-.014368,
.016939,-.013695,
.017,-.013,
.017,.013,
.016939,.013695,
.016759,.014368,
.016464,.015,
.016064,.015571,
.015571,.016064,
.015,.016464,
.014368,.016759,
.013695,.016939,
.013,.017,
-.013,.017,
-.013695,.016939,
-.014368,.016759,
-.015,.016464,
-.015571,.016064,
-.016064,.015571,
-.016464,.015,
-.016759,.014368,
-.016939,.013695,
-.017,.013,
0.0*
%
%ADD50MACRO50*%
%AMMACRO80*
4,1,3,0.0,.0125,
.025,-.0125,
-.025,-.0125,
0.0,.0125,
0.0*
%
%ADD80MACRO80*%
%ADD65R,.042X.012*%
%ADD64R,.012X.042*%
%ADD49R,.022X.04*%
%ADD68R,.012X.06*%
%ADD60R,.012X.042*%
%ADD59R,.042X.012*%
%ADD52R,.06X.014*%
%ADD76R,.105X.128*%
%ADD67R,.014X.06*%
%ADD63R,.036X.012*%
%ADD62R,.012X.036*%
%ADD74R,.012X.037*%
%ADD73R,.037X.012*%
%ADD71R,.012X.046*%
%ADD70R,.046X.012*%
%ADD58R,.012X.036*%
%ADD57R,.036X.012*%
%AMMACRO66*
4,1,40,-.004,-.007,
.004,-.007,
.004347,-.00697,
.004684,-.006879,
.005,-.006732,
.005286,-.006532,
.005532,-.006286,
.005732,-.006,
.005879,-.005684,
.00597,-.005347,
.006,-.005,
.006,.005,
.00597,.005347,
.005879,.005684,
.005732,.006,
.005532,.006286,
.005286,.006532,
.005,.006732,
.004684,.006879,
.004347,.00697,
.004,.007,
-.004,.007,
-.004347,.00697,
-.004684,.006879,
-.005,.006732,
-.005286,.006532,
-.005532,.006286,
-.005732,.006,
-.005879,.005684,
-.00597,.005347,
-.006,.005,
-.006,-.005,
-.00597,-.005347,
-.005879,-.005684,
-.005732,-.006,
-.005532,-.006286,
-.005286,-.006532,
-.005,-.006732,
-.004684,-.006879,
-.004347,-.00697,
-.004,-.007,
0.0*
%
%ADD66MACRO66*%
%ADD72R,.05X.065*%
%ADD32R,.036X.024*%
%ADD78R,.065X.05*%
%ADD28R,.081X.026*%
%ADD46R,.065X.025*%
%ADD27R,.079X.02*%
%ADD45R,.045X.055*%
%ADD39R,.048X.016*%
%ADD11R,.098X.02*%
%ADD54R,.055X.045*%
%ADD53R,.016X.048*%
%ADD22R,.047X.073*%
%ADD48R,.073X.047*%
%ADD69R,.241X.241*%
%AMMACRO77*
4,1,40,.014,.008,
.014,-.008,
.013939,-.008695,
.013759,-.009368,
.013464,-.01,
.013064,-.010571,
.012571,-.011064,
.012,-.011464,
.011368,-.011759,
.010695,-.011939,
.01,-.012,
-.01,-.012,
-.010695,-.011939,
-.011368,-.011759,
-.012,-.011464,
-.012571,-.011064,
-.013064,-.010571,
-.013464,-.01,
-.013759,-.009368,
-.013939,-.008695,
-.014,-.008,
-.014,.008,
-.013939,.008695,
-.013759,.009368,
-.013464,.01,
-.013064,.010571,
-.012571,.011064,
-.012,.011464,
-.011368,.011759,
-.010695,.011939,
-.01,.012,
.01,.012,
.010695,.011939,
.011368,.011759,
.012,.011464,
.012571,.011064,
.013064,.010571,
.013464,.01,
.013759,.009368,
.013939,.008695,
.014,.008,
0.0*
%
%ADD77MACRO77*%
%AMMACRO44*
4,1,40,-.0225,.007,
-.022378,.008389,
-.022018,.009736,
-.021428,.011,
-.020628,.012142,
-.019642,.013128,
-.0185,.013928,
-.017236,.014518,
-.015889,.014878,
-.0145,.015,
.0145,.015,
.015889,.014878,
.017236,.014518,
.0185,.013928,
.019642,.013128,
.020628,.012142,
.021428,.011,
.022018,.009736,
.022378,.008389,
.0225,.007,
.0225,-.007,
.022378,-.008389,
.022018,-.009736,
.021428,-.011,
.020628,-.012142,
.019642,-.013128,
.0185,-.013928,
.017236,-.014518,
.015889,-.014878,
.0145,-.015,
-.0145,-.015,
-.015889,-.014878,
-.017236,-.014518,
-.0185,-.013928,
-.019642,-.013128,
-.020628,-.012142,
-.021428,-.011,
-.022018,-.009736,
-.022378,-.008389,
-.0225,-.007,
-.0225,.007,
0.0*
%
%ADD44MACRO44*%
%AMMACRO43*
4,1,40,.007,.0225,
.008389,.022378,
.009736,.022018,
.011,.021428,
.012142,.020628,
.013128,.019642,
.013928,.0185,
.014518,.017236,
.014878,.015889,
.015,.0145,
.015,-.0145,
.014878,-.015889,
.014518,-.017236,
.013928,-.0185,
.013128,-.019642,
.012142,-.020628,
.011,-.021428,
.009736,-.022018,
.008389,-.022378,
.007,-.0225,
-.007,-.0225,
-.008389,-.022378,
-.009736,-.022018,
-.011,-.021428,
-.012142,-.020628,
-.013128,-.019642,
-.013928,-.0185,
-.014518,-.017236,
-.014878,-.015889,
-.015,-.0145,
-.015,.0145,
-.014878,.015889,
-.014518,.017236,
-.013928,.0185,
-.013128,.019642,
-.012142,.020628,
-.011,.021428,
-.009736,.022018,
-.008389,.022378,
-.007,.0225,
.007,.0225,
0.0*
%
%ADD43MACRO43*%
%AMMACRO25*
4,1,40,-.007,-.011,
.007,-.011,
.007695,-.010939,
.008368,-.010759,
.009,-.010464,
.009571,-.010064,
.010064,-.009571,
.010464,-.009,
.010759,-.008368,
.010939,-.007695,
.011,-.007,
.011,.007,
.010939,.007695,
.010759,.008368,
.010464,.009,
.010064,.009571,
.009571,.010064,
.009,.010464,
.008368,.010759,
.007695,.010939,
.007,.011,
-.007,.011,
-.007695,.010939,
-.008368,.010759,
-.009,.010464,
-.009571,.010064,
-.010064,.009571,
-.010464,.009,
-.010759,.008368,
-.010939,.007695,
-.011,.007,
-.011,-.007,
-.010939,-.007695,
-.010759,-.008368,
-.010464,-.009,
-.010064,-.009571,
-.009571,-.010064,
-.009,-.010464,
-.008368,-.010759,
-.007695,-.010939,
-.007,-.011,
0.0*
%
%ADD25MACRO25*%
%AMMACRO17*
4,1,40,.012,-.008,
.012,.008,
.011939,.008695,
.011759,.009368,
.011464,.01,
.011064,.010571,
.010571,.011064,
.01,.011464,
.009368,.011759,
.008695,.011939,
.008,.012,
-.008,.012,
-.008695,.011939,
-.009368,.011759,
-.01,.011464,
-.010571,.011064,
-.011064,.010571,
-.011464,.01,
-.011759,.009368,
-.011939,.008695,
-.012,.008,
-.012,-.008,
-.011939,-.008695,
-.011759,-.009368,
-.011464,-.01,
-.011064,-.010571,
-.010571,-.011064,
-.01,-.011464,
-.009368,-.011759,
-.008695,-.011939,
-.008,-.012,
.008,-.012,
.008695,-.011939,
.009368,-.011759,
.01,-.011464,
.010571,-.011064,
.011064,-.010571,
.011464,-.01,
.011759,-.009368,
.011939,-.008695,
.012,-.008,
0.0*
%
%ADD17MACRO17*%
%AMMACRO15*
4,1,40,-.008,-.012,
.008,-.012,
.008695,-.011939,
.009368,-.011759,
.01,-.011464,
.010571,-.011064,
.011064,-.010571,
.011464,-.01,
.011759,-.009368,
.011939,-.008695,
.012,-.008,
.012,.008,
.011939,.008695,
.011759,.009368,
.011464,.01,
.011064,.010571,
.010571,.011064,
.01,.011464,
.009368,.011759,
.008695,.011939,
.008,.012,
-.008,.012,
-.008695,.011939,
-.009368,.011759,
-.01,.011464,
-.010571,.011064,
-.011064,.010571,
-.011464,.01,
-.011759,.009368,
-.011939,.008695,
-.012,.008,
-.012,-.008,
-.011939,-.008695,
-.011759,-.009368,
-.011464,-.01,
-.011064,-.010571,
-.010571,-.011064,
-.01,-.011464,
-.009368,-.011759,
-.008695,-.011939,
-.008,-.012,
0.0*
%
%ADD15MACRO15*%
%AMMACRO37*
4,1,40,-.011,.007,
-.011,-.007,
-.010939,-.007695,
-.010759,-.008368,
-.010464,-.009,
-.010064,-.009571,
-.009571,-.010064,
-.009,-.010464,
-.008368,-.010759,
-.007695,-.010939,
-.007,-.011,
.007,-.011,
.007695,-.010939,
.008368,-.010759,
.009,-.010464,
.009571,-.010064,
.010064,-.009571,
.010464,-.009,
.010759,-.008368,
.010939,-.007695,
.011,-.007,
.011,.007,
.010939,.007695,
.010759,.008368,
.010464,.009,
.010064,.009571,
.009571,.010064,
.009,.010464,
.008368,.010759,
.007695,.010939,
.007,.011,
-.007,.011,
-.007695,.010939,
-.008368,.010759,
-.009,.010464,
-.009571,.010064,
-.010064,.009571,
-.010464,.009,
-.010759,.008368,
-.010939,.007695,
-.011,.007,
0.0*
%
%ADD37MACRO37*%
%AMMACRO55*
4,1,40,.013,.017,
-.013,.017,
-.013695,.016939,
-.014368,.016759,
-.015,.016464,
-.015571,.016064,
-.016064,.015571,
-.016464,.015,
-.016759,.014368,
-.016939,.013695,
-.017,.013,
-.017,-.013,
-.016939,-.013695,
-.016759,-.014368,
-.016464,-.015,
-.016064,-.015571,
-.015571,-.016064,
-.015,-.016464,
-.014368,-.016759,
-.013695,-.016939,
-.013,-.017,
.013,-.017,
.013695,-.016939,
.014368,-.016759,
.015,-.016464,
.015571,-.016064,
.016064,-.015571,
.016464,-.015,
.016759,-.014368,
.016939,-.013695,
.017,-.013,
.017,.013,
.016939,.013695,
.016759,.014368,
.016464,.015,
.016064,.015571,
.015571,.016064,
.015,.016464,
.014368,.016759,
.013695,.016939,
.013,.017,
0.0*
%
%ADD55MACRO55*%
%AMMACRO31*
4,1,40,.017,-.013,
.017,.013,
.016939,.013695,
.016759,.014368,
.016464,.015,
.016064,.015571,
.015571,.016064,
.015,.016464,
.014368,.016759,
.013695,.016939,
.013,.017,
-.013,.017,
-.013695,.016939,
-.014368,.016759,
-.015,.016464,
-.015571,.016064,
-.016064,.015571,
-.016464,.015,
-.016759,.014368,
-.016939,.013695,
-.017,.013,
-.017,-.013,
-.016939,-.013695,
-.016759,-.014368,
-.016464,-.015,
-.016064,-.015571,
-.015571,-.016064,
-.015,-.016464,
-.014368,-.016759,
-.013695,-.016939,
-.013,-.017,
.013,-.017,
.013695,-.016939,
.014368,-.016759,
.015,-.016464,
.015571,-.016064,
.016064,-.015571,
.016464,-.015,
.016759,-.014368,
.016939,-.013695,
.017,-.013,
0.0*
%
%ADD31MACRO31*%
%AMMACRO26*
4,1,40,-.007,-.011,
.007,-.011,
.007695,-.010939,
.008368,-.010759,
.009,-.010464,
.009571,-.010064,
.010064,-.009571,
.010464,-.009,
.010759,-.008368,
.010939,-.007695,
.011,-.007,
.011,.007,
.010939,.007695,
.010759,.008368,
.010464,.009,
.010064,.009571,
.009571,.010064,
.009,.010464,
.008368,.010759,
.007695,.010939,
.007,.011,
-.007,.011,
-.007695,.010939,
-.008368,.010759,
-.009,.010464,
-.009571,.010064,
-.010064,.009571,
-.010464,.009,
-.010759,.008368,
-.010939,.007695,
-.011,.007,
-.011,-.007,
-.010939,-.007695,
-.010759,-.008368,
-.010464,-.009,
-.010064,-.009571,
-.009571,-.010064,
-.009,-.010464,
-.008368,-.010759,
-.007695,-.010939,
-.007,-.011,
0.0*
%
%ADD26MACRO26*%
%AMMACRO16*
4,1,40,.012,-.008,
.012,.008,
.011939,.008695,
.011759,.009368,
.011464,.01,
.011064,.010571,
.010571,.011064,
.01,.011464,
.009368,.011759,
.008695,.011939,
.008,.012,
-.008,.012,
-.008695,.011939,
-.009368,.011759,
-.01,.011464,
-.010571,.011064,
-.011064,.010571,
-.011464,.01,
-.011759,.009368,
-.011939,.008695,
-.012,.008,
-.012,-.008,
-.011939,-.008695,
-.011759,-.009368,
-.011464,-.01,
-.011064,-.010571,
-.010571,-.011064,
-.01,-.011464,
-.009368,-.011759,
-.008695,-.011939,
-.008,-.012,
.008,-.012,
.008695,-.011939,
.009368,-.011759,
.01,-.011464,
.010571,-.011064,
.011064,-.010571,
.011464,-.01,
.011759,-.009368,
.011939,-.008695,
.012,-.008,
0.0*
%
%ADD16MACRO16*%
%AMMACRO14*
4,1,40,-.008,-.012,
.008,-.012,
.008695,-.011939,
.009368,-.011759,
.01,-.011464,
.010571,-.011064,
.011064,-.010571,
.011464,-.01,
.011759,-.009368,
.011939,-.008695,
.012,-.008,
.012,.008,
.011939,.008695,
.011759,.009368,
.011464,.01,
.011064,.010571,
.010571,.011064,
.01,.011464,
.009368,.011759,
.008695,.011939,
.008,.012,
-.008,.012,
-.008695,.011939,
-.009368,.011759,
-.01,.011464,
-.010571,.011064,
-.011064,.010571,
-.011464,.01,
-.011759,.009368,
-.011939,.008695,
-.012,.008,
-.012,-.008,
-.011939,-.008695,
-.011759,-.009368,
-.011464,-.01,
-.011064,-.010571,
-.010571,-.011064,
-.01,-.011464,
-.009368,-.011759,
-.008695,-.011939,
-.008,-.012,
0.0*
%
%ADD14MACRO14*%
%AMMACRO38*
4,1,40,-.011,.007,
-.011,-.007,
-.010939,-.007695,
-.010759,-.008368,
-.010464,-.009,
-.010064,-.009571,
-.009571,-.010064,
-.009,-.010464,
-.008368,-.010759,
-.007695,-.010939,
-.007,-.011,
.007,-.011,
.007695,-.010939,
.008368,-.010759,
.009,-.010464,
.009571,-.010064,
.010064,-.009571,
.010464,-.009,
.010759,-.008368,
.010939,-.007695,
.011,-.007,
.011,.007,
.010939,.007695,
.010759,.008368,
.010464,.009,
.010064,.009571,
.009571,.010064,
.009,.010464,
.008368,.010759,
.007695,.010939,
.007,.011,
-.007,.011,
-.007695,.010939,
-.008368,.010759,
-.009,.010464,
-.009571,.010064,
-.010064,.009571,
-.010464,.009,
-.010759,.008368,
-.010939,.007695,
-.011,.007,
0.0*
%
%ADD38MACRO38*%
%ADD82C,.02*%
%ADD83C,.006*%
G75*
%LPD*%
G75*
G36*
G01X1021245Y1493247D02*
Y1510922D01*
X995645D01*
Y1493247D01*
X1021245D01*
G37*
G36*
G01Y1473722D02*
Y1491397D01*
X995645D01*
Y1473722D01*
X1021245D01*
G37*
G36*
G01Y1453247D02*
Y1470922D01*
X995645D01*
Y1453247D01*
X1021245D01*
G37*
G36*
G01Y1433722D02*
Y1451397D01*
X995645D01*
Y1433722D01*
X1021245D01*
G37*
G36*
G01Y1573247D02*
Y1590922D01*
X995645D01*
Y1573247D01*
X1021245D01*
G37*
G36*
G01Y1553722D02*
Y1571397D01*
X995645D01*
Y1553722D01*
X1021245D01*
G37*
G36*
G01Y1533247D02*
Y1550922D01*
X995645D01*
Y1533247D01*
X1021245D01*
G37*
G36*
G01Y1513722D02*
Y1531397D01*
X995645D01*
Y1513722D01*
X1021245D01*
G37*
G36*
G01X995645Y1593722D02*
X1021244D01*
Y1610922D01*
X995645D01*
Y1593722D01*
G37*
G54D10*
X-49168Y52138D03*
X26000Y1965500D03*
X329500Y363500D03*
X327500Y1662000D03*
X404000Y432000D03*
X340500Y793500D03*
X405000Y862500D03*
X343000Y1166000D03*
X399500Y1734000D03*
X413500Y1247500D03*
X1009500Y27500D03*
X1010500Y1966000D03*
X1085741Y22661D03*
Y1967598D03*
G54D11*
X8858Y629693D03*
Y626544D03*
Y623394D03*
Y620245D03*
Y617095D03*
Y613945D03*
Y610796D03*
Y607646D03*
Y604496D03*
Y601347D03*
Y598197D03*
Y702134D03*
Y698985D03*
Y695835D03*
Y692685D03*
Y689536D03*
Y686386D03*
Y683237D03*
Y680087D03*
Y676937D03*
Y673788D03*
Y670638D03*
Y667489D03*
Y664339D03*
Y661189D03*
Y658040D03*
Y654890D03*
Y651741D03*
Y648591D03*
Y645441D03*
Y642292D03*
Y639142D03*
Y635993D03*
Y632843D03*
Y774575D03*
Y771426D03*
Y768276D03*
Y765126D03*
Y761977D03*
Y758827D03*
Y755678D03*
Y752528D03*
Y749378D03*
Y733630D03*
Y730481D03*
Y727331D03*
Y724182D03*
Y721032D03*
Y717882D03*
Y714733D03*
Y711583D03*
Y708433D03*
Y705284D03*
Y847016D03*
Y843867D03*
Y840717D03*
Y837567D03*
Y834418D03*
Y831268D03*
Y828119D03*
Y824969D03*
Y821819D03*
Y818670D03*
Y815520D03*
Y812371D03*
Y809221D03*
Y806071D03*
Y802922D03*
Y799772D03*
Y796622D03*
Y793473D03*
Y790323D03*
Y787174D03*
Y784024D03*
Y780874D03*
Y777725D03*
Y919457D03*
Y916308D03*
Y913158D03*
Y910008D03*
Y906859D03*
Y903709D03*
Y900559D03*
Y897410D03*
Y894260D03*
Y891111D03*
Y887961D03*
Y884811D03*
Y881662D03*
Y878512D03*
Y875363D03*
Y872213D03*
Y869063D03*
Y865914D03*
Y862764D03*
Y859615D03*
Y856465D03*
Y853315D03*
Y850166D03*
Y922607D03*
Y1138355D03*
Y1135205D03*
Y1132056D03*
Y1128906D03*
Y1125756D03*
Y1122607D03*
Y1119457D03*
Y1116308D03*
Y1113158D03*
Y1110008D03*
Y1106859D03*
Y1103709D03*
Y1100559D03*
Y1097410D03*
Y1094260D03*
Y1210796D03*
Y1207646D03*
Y1204496D03*
Y1201347D03*
Y1198197D03*
Y1195048D03*
Y1191898D03*
Y1188748D03*
Y1185599D03*
Y1182449D03*
Y1179300D03*
Y1176150D03*
Y1173000D03*
Y1169851D03*
Y1166701D03*
Y1163552D03*
Y1160402D03*
Y1157252D03*
Y1154103D03*
Y1150953D03*
Y1147804D03*
Y1144654D03*
Y1141504D03*
Y1283237D03*
Y1280087D03*
Y1276937D03*
Y1273788D03*
Y1270638D03*
Y1267489D03*
Y1264339D03*
Y1261189D03*
Y1258040D03*
Y1254890D03*
Y1251741D03*
Y1248591D03*
Y1245441D03*
Y1229693D03*
Y1226544D03*
Y1223394D03*
Y1220245D03*
Y1217095D03*
Y1213945D03*
Y1355678D03*
Y1352528D03*
Y1349378D03*
Y1346229D03*
Y1343079D03*
Y1339930D03*
Y1336780D03*
Y1333630D03*
Y1330481D03*
Y1327331D03*
Y1324182D03*
Y1321032D03*
Y1317882D03*
Y1314733D03*
Y1311583D03*
Y1308434D03*
Y1305284D03*
Y1302134D03*
Y1298985D03*
Y1295835D03*
Y1292685D03*
Y1289536D03*
Y1286386D03*
Y1418670D03*
Y1415520D03*
Y1412371D03*
Y1409221D03*
Y1406071D03*
Y1402922D03*
Y1399772D03*
Y1396622D03*
Y1393473D03*
Y1390323D03*
Y1387174D03*
Y1384024D03*
Y1380874D03*
Y1377725D03*
Y1374575D03*
Y1371426D03*
Y1368276D03*
Y1365126D03*
Y1361977D03*
Y1358827D03*
Y1574574D03*
Y1571425D03*
Y1568275D03*
Y1565126D03*
Y1561976D03*
Y1558826D03*
Y1555677D03*
Y1552527D03*
Y1549378D03*
Y1546228D03*
Y1543078D03*
Y1539929D03*
Y1536779D03*
Y1533630D03*
Y1530480D03*
Y1527330D03*
Y1524181D03*
Y1521031D03*
Y1517881D03*
Y1514732D03*
Y1511582D03*
Y1647015D03*
Y1643866D03*
Y1640716D03*
Y1637567D03*
Y1634417D03*
Y1631267D03*
Y1628118D03*
Y1624968D03*
Y1621818D03*
Y1618669D03*
Y1615519D03*
Y1612370D03*
Y1609220D03*
Y1606070D03*
Y1602921D03*
Y1599771D03*
Y1596622D03*
Y1593472D03*
Y1590322D03*
Y1587173D03*
Y1584023D03*
Y1580874D03*
Y1577724D03*
Y1719456D03*
Y1716307D03*
Y1713157D03*
Y1710007D03*
Y1706858D03*
Y1703708D03*
Y1700559D03*
Y1697409D03*
Y1694259D03*
Y1691110D03*
Y1687960D03*
Y1684811D03*
Y1681661D03*
Y1678511D03*
Y1675362D03*
Y1672212D03*
Y1669063D03*
Y1665913D03*
Y1662763D03*
Y1791897D03*
Y1788748D03*
Y1785598D03*
Y1782448D03*
Y1779299D03*
Y1776149D03*
Y1773000D03*
Y1769850D03*
Y1766700D03*
Y1763551D03*
Y1760401D03*
Y1757252D03*
Y1754102D03*
Y1750952D03*
Y1747803D03*
Y1744653D03*
Y1741504D03*
Y1738354D03*
Y1735204D03*
Y1732055D03*
Y1728905D03*
Y1725756D03*
Y1722606D03*
Y1835992D03*
Y1832842D03*
Y1829693D03*
Y1826543D03*
Y1823393D03*
Y1820244D03*
Y1817094D03*
Y1813944D03*
Y1810795D03*
Y1807645D03*
Y1804496D03*
Y1801346D03*
Y1798196D03*
Y1795047D03*
G54D20*
X37100Y1832100D03*
Y1827300D03*
X325900Y583400D03*
G54D21*
X31500Y1832100D03*
Y1827300D03*
X320300Y583400D03*
G54D12*
X39086Y650614D03*
X37657Y1125065D03*
X38925Y1589682D03*
X37500Y1581000D03*
X98037Y14136D03*
X87500Y202000D03*
X74711Y246388D03*
X87589Y225909D03*
X56500Y216612D03*
X87600Y209868D03*
X111436Y260164D03*
X86000Y253465D03*
X72000D03*
X64734Y217647D03*
X59750Y223465D03*
X70819Y230822D03*
X97731Y234237D03*
X106782Y268794D03*
X80300Y397700D03*
X90800D03*
X85950Y341250D03*
X90700Y349600D03*
X110600Y396300D03*
X93825Y377775D03*
X65300Y396800D03*
X108000Y456012D03*
Y448512D03*
X86500Y608100D03*
X82962Y616638D03*
X64734Y623159D03*
X61523Y630374D03*
X74711Y651900D03*
X87589Y631421D03*
X86000Y658977D03*
X72000D03*
X70621Y636334D03*
X97731Y639749D03*
X41901Y716960D03*
X44576Y724360D03*
X85950Y746750D03*
X90700Y755100D03*
X81300Y803600D03*
X89800Y803500D03*
X43555Y776945D03*
X111200Y802054D03*
X93825Y783275D03*
X70150Y803150D03*
X108000Y861524D03*
Y854024D03*
X86000Y1014200D03*
X97812Y1066417D03*
X88000Y1037507D03*
X82962Y1022149D03*
X86000Y1064488D03*
X72000D03*
X64734Y1028670D03*
X64500Y1037500D03*
X70875Y1044000D03*
X97731Y1045260D03*
X41000Y1070000D03*
X42286Y1104286D03*
X41840Y1115552D03*
X45000Y1076500D03*
X83000Y1208600D03*
X90800D03*
X40097Y1154992D03*
X85950Y1152650D03*
X90700Y1161000D03*
X111000Y1207800D03*
X93825Y1188775D03*
X68150Y1208200D03*
X108000Y1267036D03*
Y1259536D03*
X87500Y1420500D03*
X82962Y1427661D03*
X82137Y1476495D03*
X104000Y1490500D03*
Y1498500D03*
X87589Y1442444D03*
X86000Y1470000D03*
X72000D03*
X64734Y1434182D03*
X62000Y1441800D03*
X70273Y1447357D03*
X97731Y1450772D03*
X85250Y1548750D03*
X90300Y1557100D03*
X42855Y1554900D03*
X39800Y1547400D03*
X78100Y1614500D03*
X86500Y1614700D03*
X47254Y1587961D03*
X51718Y1595562D03*
X111000Y1613200D03*
X103025Y1589654D03*
X83200Y1588650D03*
X63200Y1613300D03*
X108000Y1672548D03*
Y1665048D03*
X88100Y1825000D03*
X79500Y1841400D03*
X82964Y1831400D03*
X90749Y1860311D03*
X93200Y1867400D03*
X65100Y1838100D03*
X62900Y1826400D03*
X105350Y1846300D03*
X83467Y1862457D03*
X109100Y1936300D03*
X83911Y1886506D03*
X55750Y1932750D03*
X109500Y1947700D03*
X60500Y1941100D03*
X60600Y1970300D03*
X80600Y1964000D03*
X41700Y1969400D03*
X130500Y45400D03*
X146000Y41900D03*
X180850Y22721D03*
X165700Y37800D03*
X113200Y59950D03*
X120700D03*
X112800Y49200D03*
X181387Y158953D03*
X175400Y152000D03*
X118832Y152559D03*
X141500Y140500D03*
X182582Y135000D03*
X158497Y163411D03*
X181404Y142546D03*
X155421Y142657D03*
X136795Y319578D03*
Y327078D03*
X120370Y331567D03*
X152300Y370400D03*
X164300Y377200D03*
X129975Y396346D03*
X113650Y378779D03*
X133100Y379700D03*
X149800Y397350D03*
X158150Y434350D03*
X153400Y426000D03*
X115800Y444600D03*
X141321Y541250D03*
X169000Y533500D03*
X176657Y531625D03*
X144750Y549500D03*
X181387Y564465D03*
X162300Y558100D03*
X135000Y570000D03*
X152500Y774500D03*
X136395Y725090D03*
Y732590D03*
X127500Y737100D03*
X153200Y783600D03*
X158150Y839850D03*
X153400Y831100D03*
X130350Y802221D03*
X113650Y784279D03*
X132900Y783900D03*
X150175Y803225D03*
X117000Y849400D03*
X183838Y968275D03*
X172705Y952750D03*
X171477Y965000D03*
X150000Y955000D03*
X161226Y971250D03*
X161512Y963755D03*
X135895Y1130602D03*
Y1138102D03*
X153400Y1189700D03*
X166100Y1189800D03*
X127500Y1142500D03*
X130350Y1207721D03*
X113650Y1189779D03*
X133100Y1191700D03*
X150175Y1208725D03*
X158450Y1245350D03*
X153700Y1237000D03*
X116300Y1255500D03*
X144375Y1357194D03*
X181404Y1357558D03*
X155000Y1357835D03*
X181300Y1374800D03*
X175554Y1367159D03*
X181500Y1382400D03*
X158497Y1379946D03*
X169100Y1371600D03*
X114000Y1482000D03*
X122000D03*
X130000D03*
X135695Y1536114D03*
Y1543614D03*
X122500Y1547400D03*
X155000Y1583800D03*
X154900Y1591300D03*
Y1642500D03*
X130350Y1613221D03*
X123042Y1583449D03*
X150175Y1614225D03*
X159650Y1650850D03*
X121950Y1661250D03*
X181387Y1781000D03*
X175000Y1774500D03*
X171506Y1763994D03*
X165000Y1774000D03*
X131795Y1932826D03*
Y1940326D03*
X138100Y1946000D03*
X143450Y1975664D03*
X200675Y23725D03*
X206750Y60250D03*
X201600Y51900D03*
X186487Y164453D03*
X203154Y139453D03*
X187608Y154749D03*
X186400Y368300D03*
X193750Y535250D03*
X194000Y527750D03*
Y555125D03*
X191500Y543500D03*
X186487Y569965D03*
X187500Y559000D03*
X217200Y565700D03*
X187800Y775400D03*
X212300Y961000D03*
X186487Y975477D03*
X191000Y964300D03*
X191500Y942500D03*
X188000Y1179500D03*
X186100Y1346600D03*
X199900Y1346488D03*
X186700Y1585700D03*
X201447Y1751500D03*
X228181Y1772100D03*
X186400Y1786700D03*
X190266Y1776603D03*
X194750Y1762000D03*
X210500Y1761400D03*
X287951Y93246D03*
X315100Y403400D03*
X291955Y505017D03*
X315400Y598400D03*
X314000Y587000D03*
X320900Y593000D03*
X306500Y568400D03*
X315000Y571000D03*
Y578500D03*
X314000Y834000D03*
X314600Y1204800D03*
X313500Y1406300D03*
X301500Y1407500D03*
X307400Y1400800D03*
X285100Y1412200D03*
X285700Y1404100D03*
X293200Y1406100D03*
X272722Y1584801D03*
X276500Y1709400D03*
X269000Y1709516D03*
X315200Y1704900D03*
X287500Y1783000D03*
X279500D03*
X271500D03*
X276500Y1740000D03*
X271000Y1745500D03*
X282000D03*
X352500Y81500D03*
X348500Y118500D03*
X355000Y112000D03*
X363500Y81500D03*
X367250Y63000D03*
X368800Y88300D03*
X368350Y104650D03*
X380250Y336100D03*
X344750D03*
X388250Y336000D03*
X352750D03*
X381500Y357500D03*
X346000D03*
X343500Y393000D03*
X345900Y376000D03*
X333300Y403400D03*
X339000Y379000D03*
X343000Y385500D03*
X355250Y463900D03*
X390750D03*
X354000Y442500D03*
X389500D03*
X347250Y464000D03*
X382750D03*
X333500Y421000D03*
Y413000D03*
X340500Y425000D03*
X373750Y766100D03*
X381750Y766000D03*
X375100Y787700D03*
X333500Y843000D03*
X343500Y823000D03*
X345300Y804400D03*
X379600Y795300D03*
X333800Y833000D03*
X339000Y809000D03*
X343000Y815500D03*
X355250Y893900D03*
X390750D03*
X354000Y872500D03*
X389500D03*
X347250Y894000D03*
X382750D03*
X333500Y851000D03*
X340500Y855000D03*
X348861Y1070104D03*
X380250Y1137600D03*
X388250Y1137500D03*
X381500Y1159000D03*
X343500Y1194500D03*
X345600Y1176100D03*
X385900Y1166100D03*
X334500Y1204250D03*
X339000Y1180500D03*
X343000Y1187000D03*
X355029Y1265402D03*
X390750Y1265400D03*
X354000Y1244000D03*
X389500D03*
X347250Y1265500D03*
X382750D03*
X333500Y1222500D03*
Y1214500D03*
X340500Y1226500D03*
X344750Y1636100D03*
X352750Y1636000D03*
X346000Y1657500D03*
X333500Y1721000D03*
Y1713000D03*
X344000Y1693600D03*
X346000Y1676500D03*
X333600Y1703500D03*
X339100Y1679600D03*
X342700Y1686200D03*
X355250Y1763900D03*
X354000Y1742500D03*
X347250Y1764000D03*
X340500Y1725000D03*
X406000Y399000D03*
X474300Y423688D03*
X433900Y809250D03*
X412500Y810500D03*
X434000Y817250D03*
X433900Y1211750D03*
X412500Y1213000D03*
X434000Y1219750D03*
X433900Y1710250D03*
X412500Y1711500D03*
X434000Y1718250D03*
X486363Y932790D03*
X668643Y131315D03*
X763200Y1698600D03*
X820500Y183000D03*
X828500D03*
X836500D03*
X810500Y191500D03*
Y199500D03*
X814250Y341250D03*
X819000Y349600D03*
X820325Y377775D03*
X814250Y746750D03*
X819000Y755100D03*
X820325Y783275D03*
X814250Y1152250D03*
X819000Y1160600D03*
X820325Y1188775D03*
X814250Y1557750D03*
X819200Y1566100D03*
X820325Y1594275D03*
X826888Y1714000D03*
X835888Y1716500D03*
X829888Y1721000D03*
X819000Y1797000D03*
X829500D03*
X837500D03*
X810500Y1805500D03*
Y1813500D03*
X779089Y1931757D03*
X783939Y1940107D03*
X835800Y1948500D03*
X835000Y1941000D03*
X788389Y1969286D03*
X808339Y1962507D03*
X768564Y1968282D03*
X909733Y158953D03*
X904728Y151181D03*
X883412Y149000D03*
X909881Y131990D03*
X879000Y169500D03*
X910750Y141223D03*
X884000Y140013D03*
X863941Y319578D03*
Y327078D03*
X850125Y330750D03*
X882500Y367000D03*
X894900Y377300D03*
X840150Y378779D03*
X861890Y383014D03*
X903728Y556693D03*
X881500Y548965D03*
X907492Y536837D03*
X909750Y546735D03*
X880636Y541514D03*
X909733Y564465D03*
X886843Y568923D03*
X882000Y773000D03*
X863841Y725090D03*
Y732590D03*
X851150Y736750D03*
X894800Y783900D03*
X840150Y784279D03*
X859737Y789667D03*
X909733Y969977D03*
X903728Y962205D03*
X881500Y954477D03*
X890550Y957450D03*
X908177Y942729D03*
X879800Y975800D03*
X909750Y952247D03*
X880636Y947026D03*
X864241Y1130602D03*
Y1138102D03*
X880500Y1178500D03*
X886400Y1185000D03*
X849550Y1142150D03*
X840150Y1189779D03*
X860272Y1194370D03*
X852898Y1249029D03*
X908530Y1348458D03*
X909750Y1357758D03*
X880636Y1352537D03*
X909733Y1375488D03*
X903900Y1367659D03*
X881500Y1359988D03*
X880100Y1380100D03*
X864441Y1536114D03*
Y1543614D03*
X850550Y1547750D03*
X883000Y1582500D03*
X885300Y1590300D03*
X840150Y1595279D03*
X858185Y1601013D03*
X911800Y1684000D03*
X909700Y1719000D03*
X879100Y1715100D03*
X896500Y1696300D03*
X906000Y1703400D03*
X889600Y1691900D03*
X904276Y1696100D03*
X903728Y1773228D03*
X881500Y1765500D03*
X909733Y1781000D03*
X898089Y1745256D03*
X894484Y1722200D03*
X886843Y1785458D03*
X909750Y1763270D03*
X881636Y1757549D03*
X862241Y1934326D03*
Y1941826D03*
X856900Y1947600D03*
X871750Y1975500D03*
X914833Y164453D03*
X931500Y139453D03*
X915037Y153502D03*
X915900Y368600D03*
X931500Y544965D03*
X916600Y556600D03*
X914833Y569965D03*
X915800Y774600D03*
X914833Y975477D03*
X931500Y950477D03*
X914646Y964214D03*
X919100Y1180600D03*
X931500Y1355988D03*
X914833Y1380988D03*
X915037Y1370037D03*
X969000Y1641500D03*
X976000Y1636000D03*
X918600Y1584600D03*
X969500Y1676500D03*
X916200Y1708700D03*
X914833Y1786500D03*
X913923Y1752000D03*
X931500Y1761500D03*
X916100Y1773800D03*
G54D30*
X100000Y119200D03*
Y525200D03*
Y930200D03*
Y1335200D03*
Y1749700D03*
X131000Y51000D03*
X144000Y241700D03*
X146600Y357500D03*
X144000Y648200D03*
X146500Y762300D03*
X144000Y1053700D03*
X148500Y1168700D03*
X144000Y1458200D03*
X136700Y1574200D03*
X144000Y1864200D03*
X118500Y1961800D03*
X865500Y357200D03*
X872500Y648200D03*
X865000Y763100D03*
X872500Y1053700D03*
X874500Y1169200D03*
X872500Y1459200D03*
X866000Y1574700D03*
X910500Y1707700D03*
X855000Y1696700D03*
X878000Y1723200D03*
X871500Y1864200D03*
X846500Y1961700D03*
G54D31*
X100000Y124800D03*
Y530800D03*
Y935800D03*
Y1340800D03*
Y1755300D03*
X131000Y56600D03*
X144000Y247300D03*
X146600Y363100D03*
X144000Y653800D03*
X146500Y767900D03*
X144000Y1059300D03*
X148500Y1174300D03*
X144000Y1463800D03*
X136700Y1579800D03*
X144000Y1869800D03*
X118500Y1967400D03*
X865500Y362800D03*
X872500Y653800D03*
X865000Y768700D03*
X872500Y1059300D03*
X874500Y1174800D03*
X872500Y1464800D03*
X866000Y1580300D03*
X910500Y1713300D03*
X855000Y1702300D03*
X878000Y1728800D03*
X871500Y1869800D03*
X846500Y1967300D03*
G54D22*
X40184Y1865200D03*
X29216D03*
X40184Y1852900D03*
X29216D03*
X40184Y1840600D03*
X29216D03*
X40184Y1877500D03*
X29216D03*
X878859Y1671037D03*
X889827D03*
X878859Y1683500D03*
X889827D03*
G54D40*
X99700Y344800D03*
Y750300D03*
Y1156200D03*
X99000Y1552300D03*
X69500Y1936300D03*
X175894Y141463D03*
X145700Y340200D03*
X145800Y745900D03*
X182000Y956300D03*
X145800Y1150400D03*
X175894Y1356598D03*
X145800Y1554100D03*
X133200Y1954500D03*
X373500Y104800D03*
X374300Y88200D03*
X372000Y371300D03*
X368500D03*
X393500Y418300D03*
X343000Y420300D03*
X346500D03*
X362000Y803800D03*
X393500Y848300D03*
X365500Y803800D03*
X343000Y850300D03*
X346500D03*
X367500Y1174800D03*
X371000D03*
X393500Y1225300D03*
X343000Y1221800D03*
X346500D03*
X376000Y1673800D03*
X343000Y1720300D03*
X346500D03*
X372500Y1673800D03*
X828000Y344800D03*
Y750300D03*
Y1155800D03*
Y1561300D03*
X792839Y1935307D03*
X905240Y140063D03*
X874200Y340300D03*
X904240Y545575D03*
X874100Y746800D03*
X904240Y951087D03*
X874100Y1151300D03*
X904240Y1356598D03*
X874200Y1557500D03*
X841500Y1702300D03*
X904240Y1762110D03*
X862500Y1955100D03*
X994600Y1421100D03*
G54D13*
X31707Y1062791D03*
Y1081291D03*
X41100Y1633650D03*
Y1615150D03*
G54D14*
X30200Y1488300D03*
X26600D03*
X32850Y1510400D03*
X36350D03*
X82000Y243688D03*
X98400Y435600D03*
X82000Y649200D03*
X98400Y841100D03*
X83248Y1052836D03*
X98400Y1246600D03*
X82748Y1458348D03*
X98900Y1652500D03*
X54872Y1674748D03*
X58372D03*
X115700Y40000D03*
X144400Y430800D03*
Y836300D03*
X144700Y1241800D03*
X145900Y1647300D03*
X193000Y56700D03*
X194606Y1769390D03*
X395600Y398100D03*
X393500Y380200D03*
X341000Y402700D03*
X344500D03*
X368500Y429200D03*
X372000D03*
X341000Y832700D03*
X344500D03*
X393500Y829700D03*
X368500Y858200D03*
X372000D03*
X393500Y1177700D03*
X341000Y1204200D03*
X344500D03*
X395600Y1198700D03*
X368500Y1229700D03*
X372000D03*
X395700Y1697200D03*
X341000Y1702700D03*
X344500D03*
X369000Y1727700D03*
X372500D03*
X417500Y809200D03*
Y817200D03*
Y1211700D03*
Y1219700D03*
Y1710200D03*
Y1718200D03*
G54D32*
X75710Y209868D03*
Y206668D03*
X69960Y209868D03*
Y206668D03*
X75710Y615380D03*
Y612180D03*
X69960Y615380D03*
Y612180D03*
X75710Y1020891D03*
Y1017691D03*
X69960Y1020891D03*
Y1017691D03*
X75710Y1426403D03*
Y1423203D03*
X69960Y1426403D03*
Y1423203D03*
X75710Y1831915D03*
Y1828715D03*
X69960Y1831915D03*
Y1828715D03*
X174135Y163411D03*
Y160211D03*
X168385Y163411D03*
Y160211D03*
X174135Y568923D03*
Y565723D03*
X168385Y568923D03*
Y565723D03*
X174135Y974435D03*
Y971235D03*
X168385Y974435D03*
Y971235D03*
X174135Y1379946D03*
Y1376746D03*
X168385Y1379946D03*
Y1376746D03*
X174135Y1785458D03*
Y1782258D03*
X168385Y1785458D03*
Y1782258D03*
X902481Y163411D03*
Y160211D03*
X896731Y163411D03*
Y160211D03*
X902481Y568923D03*
Y565723D03*
X896731Y568923D03*
Y565723D03*
X902481Y974435D03*
Y971235D03*
X896731Y974435D03*
Y971235D03*
X902481Y1379946D03*
Y1376746D03*
X896731Y1379946D03*
Y1376746D03*
X902481Y1785458D03*
Y1782258D03*
X896731Y1785458D03*
Y1782258D03*
G54D50*
X108400Y417600D03*
X108700Y823100D03*
X97600Y1229200D03*
X108600Y1633800D03*
X297600Y1401300D03*
X288000Y1751800D03*
X293000D03*
X872500Y250800D03*
X896500Y1690800D03*
X877000Y1700800D03*
X901500Y1690800D03*
X959000Y1627200D03*
X990500Y1422300D03*
G54D41*
X99700Y341200D03*
Y746700D03*
Y1152600D03*
X99000Y1548700D03*
X69500Y1932700D03*
X175894Y137863D03*
X145700Y336600D03*
X145800Y742300D03*
X182000Y952700D03*
X145800Y1146800D03*
X175894Y1352998D03*
X145800Y1550500D03*
X133200Y1950900D03*
X373500Y101200D03*
X374300Y84600D03*
X372000Y367700D03*
X368500D03*
X393500Y414700D03*
X343000Y416700D03*
X346500D03*
X362000Y800200D03*
X393500Y844700D03*
X365500Y800200D03*
X343000Y846700D03*
X346500D03*
X367500Y1171200D03*
X371000D03*
X393500Y1221700D03*
X343000Y1218200D03*
X346500D03*
X376000Y1670200D03*
X343000Y1716700D03*
X346500D03*
X372500Y1670200D03*
X828000Y341200D03*
Y746700D03*
Y1152200D03*
Y1557700D03*
X792839Y1931707D03*
X905240Y136463D03*
X874200Y336700D03*
X904240Y541975D03*
X874100Y743200D03*
X904240Y947487D03*
X874100Y1147700D03*
X904240Y1352998D03*
X874200Y1553900D03*
X841500Y1698700D03*
X904240Y1758510D03*
X862500Y1951500D03*
X994600Y1417500D03*
G54D23*
X37300Y1964000D03*
X87589Y234415D03*
X76750Y234272D03*
X83589Y234415D03*
X63903Y212595D03*
X95700Y344700D03*
X90000Y372700D03*
X92500Y606700D03*
X63623Y614570D03*
X87589Y639927D03*
X76750Y639784D03*
X83589Y639927D03*
X95700Y750200D03*
X90000Y778200D03*
X45000Y1064200D03*
X41000D03*
X88000Y1046200D03*
X77750Y1044295D03*
X93000Y1012200D03*
X84000Y1046200D03*
X64040Y1023685D03*
X95700Y1156100D03*
X90000Y1183700D03*
X63797Y1429188D03*
X110000Y1476700D03*
X87589Y1450950D03*
X76750Y1450807D03*
X83589Y1450950D03*
X95000Y1552200D03*
X79375Y1583575D03*
X75256Y1587075D03*
X103025Y1584725D03*
X65500Y1936200D03*
X48000Y1884200D03*
X52000D03*
X61050Y1965250D03*
X114300Y69200D03*
X119300D03*
X121600Y51300D03*
X170402Y151153D03*
X163994Y154736D03*
X126445Y335017D03*
X113650Y373850D03*
X149125Y405825D03*
X152900Y434300D03*
X125300Y444500D03*
X150000Y544700D03*
X154500D03*
X162144Y575235D03*
X122445Y740617D03*
X152900Y839800D03*
X113650Y779350D03*
X149500Y811700D03*
X126800Y849000D03*
X113650Y1184850D03*
X122400Y1146000D03*
X153200Y1245300D03*
X149500Y1217200D03*
X126000Y1255500D03*
X170402Y1366688D03*
X164066Y1371527D03*
X126000Y1476700D03*
X118000D03*
X149500Y1622700D03*
X154400Y1650800D03*
X126900Y1661200D03*
X126500Y1947200D03*
X200000Y32200D03*
X201500Y60200D03*
X199000Y538700D03*
Y531200D03*
Y546200D03*
X229500Y953177D03*
X305100Y404000D03*
X309300Y396500D03*
X290580Y565700D03*
X298450D03*
X317500D03*
X304500Y833500D03*
X308600Y826000D03*
X305200Y1204950D03*
X309300Y1197450D03*
X293100Y1390200D03*
X284900D03*
X319500Y1395700D03*
X315500D03*
X287000Y1399200D03*
X291000D03*
X307500Y1395700D03*
X276500Y1717700D03*
X272500D03*
X306200Y1703450D03*
X310300Y1695950D03*
X287500Y1791700D03*
X279500D03*
X271500D03*
X358000Y70700D03*
X348500Y75200D03*
X382200Y88100D03*
X382000Y104700D03*
X348500Y127200D03*
X352500D03*
X353000Y348700D03*
X388500D03*
X345000D03*
X380500D03*
X344500Y435700D03*
X340500D03*
X359500D03*
X355500D03*
X395000D03*
X391000D03*
X376000D03*
X380000D03*
X382000Y778700D03*
X374000D03*
X355500Y865700D03*
X340500D03*
X344500D03*
X359500D03*
X380000D03*
X395000D03*
X376000D03*
X391000D03*
X388500Y1150200D03*
X380500D03*
X355500Y1237200D03*
X380000D03*
X376000D03*
X395000D03*
X391000D03*
X344500D03*
X340500D03*
X359500D03*
X353000Y1648700D03*
X345000D03*
X344500Y1735700D03*
X340500D03*
X359500D03*
X355500D03*
X764739Y1963207D03*
X832500Y177700D03*
X824500D03*
X816500D03*
X824000Y344700D03*
X816500Y372700D03*
X824000Y750200D03*
X816500Y778200D03*
X824000Y1155700D03*
X816500Y1183700D03*
X824000Y1561200D03*
X816500Y1589200D03*
X825500Y1791700D03*
X815000D03*
X788839Y1935207D03*
X788389Y1964357D03*
X899648Y150653D03*
X856200Y334200D03*
X840150Y373850D03*
X898754Y556165D03*
X856100Y740200D03*
X840150Y779350D03*
X898648Y961677D03*
X889909Y977307D03*
X840150Y1184850D03*
X854500Y1145600D03*
X898748Y1367188D03*
X890213Y1379896D03*
X855500Y1551200D03*
X840150Y1590350D03*
X881500Y1699700D03*
X898800Y1772700D03*
X906500Y1730700D03*
X890500D03*
X841500Y1791700D03*
X959000Y1663700D03*
G54D15*
X30200Y1491900D03*
X26600D03*
X32850Y1514000D03*
X36350D03*
X82000Y247288D03*
X98400Y439200D03*
X82000Y652800D03*
X98400Y844700D03*
X83248Y1056436D03*
X98400Y1250200D03*
X82748Y1461948D03*
X98900Y1656100D03*
X54872Y1678348D03*
X58372D03*
X115700Y43600D03*
X144400Y434400D03*
Y839900D03*
X144700Y1245400D03*
X145900Y1650900D03*
X193000Y60300D03*
X194606Y1772990D03*
X395600Y401700D03*
X393500Y383800D03*
X341000Y406300D03*
X344500D03*
X368500Y432800D03*
X372000D03*
X341000Y836300D03*
X344500D03*
X393500Y833300D03*
X368500Y861800D03*
X372000D03*
X393500Y1181300D03*
X341000Y1207800D03*
X344500D03*
X395600Y1202300D03*
X368500Y1233300D03*
X372000D03*
X395700Y1700800D03*
X341000Y1706300D03*
X344500D03*
X369000Y1731300D03*
X372500D03*
X417500Y812800D03*
Y820800D03*
Y1215300D03*
Y1223300D03*
Y1713800D03*
Y1721800D03*
G54D60*
X302953Y577700D03*
X300984D03*
X299016D03*
X297047D03*
Y593300D03*
X299016D03*
X300984D03*
X302953D03*
G54D24*
X37300Y1960600D03*
X87589Y231015D03*
X76750Y230872D03*
X83589Y231015D03*
X63903Y209195D03*
X95700Y341300D03*
X90000Y369300D03*
X92500Y603300D03*
X63623Y611170D03*
X87589Y636527D03*
X76750Y636384D03*
X83589Y636527D03*
X95700Y746800D03*
X90000Y774800D03*
X45000Y1060800D03*
X41000D03*
X88000Y1042800D03*
X77750Y1040895D03*
X93000Y1008800D03*
X84000Y1042800D03*
X64040Y1020285D03*
X95700Y1152700D03*
X90000Y1180300D03*
X63797Y1425788D03*
X110000Y1473300D03*
X87589Y1447550D03*
X76750Y1447407D03*
X83589Y1447550D03*
X95000Y1548800D03*
X79375Y1580175D03*
X75256Y1583675D03*
X103025Y1581325D03*
X65500Y1932800D03*
X48000Y1880800D03*
X52000D03*
X61050Y1961850D03*
X121600Y47900D03*
X114300Y65800D03*
X119300D03*
X170402Y147753D03*
X163994Y151336D03*
X126445Y331617D03*
X113650Y370450D03*
X149125Y402425D03*
X152900Y430900D03*
X125300Y441100D03*
X150000Y541300D03*
X154500D03*
X162144Y571835D03*
X122445Y737217D03*
X152900Y836400D03*
X113650Y775950D03*
X149500Y808300D03*
X126800Y845600D03*
X113650Y1181450D03*
X122400Y1142600D03*
X153200Y1241900D03*
X149500Y1213800D03*
X126000Y1252100D03*
X170402Y1363288D03*
X164066Y1368127D03*
X126000Y1473300D03*
X118000D03*
X154400Y1647400D03*
X149500Y1619300D03*
X126900Y1657800D03*
X126500Y1943800D03*
X200000Y28800D03*
X201500Y56800D03*
X199000Y535300D03*
Y527800D03*
Y542800D03*
X229500Y949777D03*
X305100Y400600D03*
X309300Y393100D03*
X290580Y562300D03*
X298450D03*
X317500D03*
X304500Y830100D03*
X308600Y822600D03*
X305200Y1201550D03*
X309300Y1194050D03*
X293100Y1386800D03*
X284900D03*
X319500Y1392300D03*
X315500D03*
X287000Y1395800D03*
X291000D03*
X307500Y1392300D03*
X276500Y1714300D03*
X272500D03*
X306200Y1700050D03*
X310300Y1692550D03*
X287500Y1788300D03*
X279500D03*
X271500D03*
X358000Y67300D03*
X348500Y71800D03*
X382200Y84700D03*
X382000Y101300D03*
X348500Y123800D03*
X352500D03*
X353000Y345300D03*
X388500D03*
X345000D03*
X380500D03*
X344500Y432300D03*
X340500D03*
X359500D03*
X355500D03*
X395000D03*
X391000D03*
X376000D03*
X380000D03*
X382000Y775300D03*
X374000D03*
X355500Y862300D03*
X340500D03*
X344500D03*
X359500D03*
X380000D03*
X395000D03*
X376000D03*
X391000D03*
X388500Y1146800D03*
X380500D03*
X355500Y1233800D03*
X380000D03*
X376000D03*
X395000D03*
X391000D03*
X344500D03*
X340500D03*
X359500D03*
X353000Y1645300D03*
X345000D03*
X344500Y1732300D03*
X340500D03*
X359500D03*
X355500D03*
X764739Y1959807D03*
X832500Y174300D03*
X824500D03*
X816500D03*
X824000Y341300D03*
X816500Y369300D03*
X824000Y746800D03*
X816500Y774800D03*
X824000Y1152300D03*
X816500Y1180300D03*
X824000Y1557800D03*
X816500Y1585800D03*
X825500Y1788300D03*
X815000D03*
X788839Y1931807D03*
X788389Y1960957D03*
X899648Y147253D03*
X856200Y330800D03*
X840150Y370450D03*
X898754Y552765D03*
X856100Y736800D03*
X840150Y775950D03*
X898648Y958277D03*
X889909Y973907D03*
X840150Y1181450D03*
X854500Y1142200D03*
X898748Y1363788D03*
X890213Y1376496D03*
X855500Y1547800D03*
X840150Y1586950D03*
X881500Y1696300D03*
X898800Y1769300D03*
X906500Y1727300D03*
X890500D03*
X841500Y1788300D03*
X959000Y1660300D03*
G54D42*
X108400Y412000D03*
X108700Y817500D03*
X97600Y1223600D03*
X108600Y1628200D03*
X297600Y1395700D03*
X288000Y1746200D03*
X293000D03*
X872500Y245200D03*
X896500Y1685200D03*
X877000Y1695200D03*
X901500Y1685200D03*
X959000Y1621600D03*
X990500Y1416700D03*
G54D33*
X73208Y220484D03*
X80708Y216609D03*
Y224359D03*
X94250Y223965D03*
X101750Y220090D03*
Y227840D03*
X94250Y629477D03*
X101750Y625602D03*
X73208Y625996D03*
X80708Y622121D03*
Y629871D03*
X101750Y633352D03*
X94250Y1034988D03*
X101750Y1031113D03*
Y1038863D03*
X73208Y1031507D03*
X80708Y1027632D03*
Y1035382D03*
X94250Y1440500D03*
X101750Y1436625D03*
Y1444375D03*
X73208Y1437019D03*
X80708Y1433144D03*
Y1440894D03*
X167250Y27600D03*
X174750Y23725D03*
Y31475D03*
X116375Y401225D03*
X123875Y397350D03*
Y405100D03*
X135875Y401225D03*
X143375Y397350D03*
Y405100D03*
X116750Y807100D03*
X124250Y803225D03*
Y810975D03*
X136250Y807100D03*
X143750Y803225D03*
Y810975D03*
X116750Y1212600D03*
X124250Y1208725D03*
X136250Y1212600D03*
X143750Y1208725D03*
X124250Y1216475D03*
X143750D03*
X136250Y1618100D03*
X143750Y1614225D03*
Y1621975D03*
X116750Y1618100D03*
X124250Y1614225D03*
Y1621975D03*
X180596Y1763500D03*
X186750Y27600D03*
X194250Y23725D03*
Y31475D03*
X209750Y555125D03*
X202250Y559000D03*
X209750Y562875D03*
X188096Y1759625D03*
Y1767375D03*
G54D51*
X104000Y1482000D03*
X154500Y536000D03*
X358000Y76000D03*
X810500Y183000D03*
Y1797000D03*
G54D16*
X33000Y1778850D03*
Y1775350D03*
X80187Y1854268D03*
X180800Y553500D03*
X128300Y1502000D03*
X360800Y120500D03*
Y117000D03*
X367300Y76500D03*
X390800Y447500D03*
X355300D03*
X382800D03*
X347300D03*
X390800Y877500D03*
X355300D03*
X382800D03*
X347300D03*
X390800Y1249000D03*
X355300D03*
X382800D03*
X347300D03*
X355300Y1747500D03*
X347300D03*
X834800Y203000D03*
Y1817000D03*
X889300Y1698000D03*
X915300Y1691000D03*
Y1699000D03*
G54D25*
X36775Y1970275D03*
X88875Y377775D03*
Y783275D03*
X66895Y1012436D03*
X88875Y1188775D03*
X67540Y1417910D03*
X96200Y1497000D03*
Y1492000D03*
X87800Y1840600D03*
X97800Y1839900D03*
X87800Y1836300D03*
X88300Y1867400D03*
X148100Y426600D03*
X119200Y454500D03*
Y449500D03*
X170700Y556330D03*
X170695Y560416D03*
X148100Y832100D03*
X119200Y860000D03*
Y855000D03*
X169617Y960000D03*
X168230Y979729D03*
X148400Y1237600D03*
X119200Y1265500D03*
Y1260500D03*
X154659Y1352302D03*
Y1347802D03*
X112500Y1543700D03*
X149600Y1643100D03*
X119200Y1671000D03*
Y1666000D03*
X122400Y1943900D03*
X196700Y52500D03*
X193700Y135000D03*
X203700Y569000D03*
X194854Y1346488D03*
X328200Y408500D03*
Y404400D03*
Y421000D03*
Y417000D03*
Y425000D03*
X329200Y609000D03*
Y597000D03*
X280200Y573000D03*
Y565000D03*
Y585000D03*
Y577000D03*
Y597000D03*
Y589000D03*
X329200D03*
X328200Y838500D03*
Y847000D03*
Y834400D03*
Y851000D03*
Y855000D03*
Y1210000D03*
Y1205800D03*
Y1222500D03*
Y1218500D03*
Y1226500D03*
X280200Y1419500D03*
Y1411500D03*
Y1423500D03*
Y1403500D03*
Y1431500D03*
X328200Y1721000D03*
Y1708500D03*
Y1717000D03*
Y1704300D03*
X272200Y1722000D03*
X328200Y1725000D03*
X367200Y58000D03*
X334200Y377000D03*
X338200Y389000D03*
X334200Y381000D03*
Y385000D03*
X390700Y459000D03*
X355200D03*
X382700D03*
X347200D03*
X334200Y807000D03*
X338200Y819000D03*
X334200Y815000D03*
Y811000D03*
X390700Y889000D03*
X355200D03*
X382700D03*
X347200D03*
X338200Y1190500D03*
X334200Y1178500D03*
Y1182500D03*
Y1186500D03*
X390700Y1260500D03*
X355200D03*
X382700D03*
X347200D03*
X334200Y1677000D03*
X338200Y1691000D03*
X334200Y1681000D03*
Y1685000D03*
X355200Y1759000D03*
X347200D03*
X405700Y820000D03*
Y805000D03*
Y824000D03*
Y809000D03*
Y1207500D03*
Y1211500D03*
Y1222500D03*
Y1226500D03*
Y1721000D03*
Y1706000D03*
Y1710000D03*
Y1725000D03*
X763614Y1968282D03*
X802700Y193000D03*
Y198000D03*
X815375Y377775D03*
Y783275D03*
Y1188775D03*
Y1594275D03*
X802700Y1812000D03*
Y1807000D03*
X889700Y157000D03*
Y161000D03*
X898675Y154724D03*
X890516Y168354D03*
X865200Y553465D03*
X887950Y556715D03*
Y560715D03*
X896941Y560408D03*
X865200Y958977D03*
X887950Y962227D03*
Y966227D03*
X897174Y965913D03*
X865200Y1364488D03*
X887388Y1365200D03*
Y1369700D03*
X896785Y1371351D03*
X887950Y1773250D03*
X865200Y1770000D03*
X887950Y1777250D03*
X897100Y1776900D03*
X851300Y1945200D03*
X923200Y129953D03*
Y535465D03*
Y940977D03*
Y1346488D03*
X954700Y1668500D03*
Y1663500D03*
X919200Y1715000D03*
X923200Y1752000D03*
G54D43*
X95700Y355250D03*
X99575Y362750D03*
X91825D03*
X95700Y760750D03*
X99575Y768250D03*
X91825D03*
X95700Y1166650D03*
X99575Y1174150D03*
X91825D03*
X95000Y1562750D03*
X98875Y1570250D03*
X91125D03*
X67600Y1844650D03*
X71475Y1852150D03*
X63725D03*
X65500Y1946750D03*
X69375Y1954250D03*
X61625D03*
X151000Y148750D03*
X154875Y156250D03*
X147125D03*
X140000Y556250D03*
X143875Y563750D03*
X136125D03*
X155000Y1364285D03*
X158875Y1371785D03*
X151125D03*
X191500Y140750D03*
X195375Y148250D03*
X187625D03*
X205000Y945227D03*
X208875Y952727D03*
X201125D03*
X219500Y945227D03*
X223375Y952727D03*
X215625D03*
X192154Y1353738D03*
X196029Y1361238D03*
X188279D03*
X221000Y1756250D03*
X224875Y1763750D03*
X217125D03*
X235500Y1756250D03*
X239375Y1763750D03*
X231625D03*
X824000Y355250D03*
X820125Y362750D03*
X827875D03*
X824000Y760750D03*
X820125Y768250D03*
X827875D03*
X824000Y1166250D03*
X820125Y1173750D03*
X827875D03*
X824000Y1571750D03*
X820125Y1579250D03*
X827875D03*
X788839Y1945757D03*
X784964Y1953257D03*
X792714D03*
X920500Y137203D03*
X916625Y144703D03*
X924375D03*
X920500Y542715D03*
X916625Y550215D03*
X924375D03*
X920500Y948227D03*
X916625Y955727D03*
X924375D03*
X920500Y1353738D03*
X916625Y1361238D03*
X924375D03*
X920500Y1759250D03*
X924375Y1766750D03*
X916625D03*
G54D70*
X352585Y410825D03*
Y408860D03*
Y406890D03*
Y404920D03*
Y402955D03*
Y400985D03*
Y399015D03*
Y397045D03*
Y395080D03*
Y393110D03*
Y391140D03*
Y389175D03*
Y387205D03*
X387415D03*
Y389175D03*
Y391140D03*
Y393110D03*
Y395080D03*
Y397045D03*
Y399015D03*
Y400985D03*
Y402955D03*
Y404920D03*
Y406890D03*
Y408860D03*
Y410825D03*
X352585Y412795D03*
X387415D03*
X352585Y842795D03*
Y840825D03*
Y838860D03*
Y836890D03*
Y834920D03*
Y832955D03*
Y830985D03*
Y829015D03*
Y827045D03*
Y825080D03*
Y823110D03*
Y821140D03*
Y819175D03*
Y817205D03*
X387415D03*
Y819175D03*
Y821140D03*
Y823110D03*
Y825080D03*
Y827045D03*
Y829015D03*
Y830985D03*
Y832955D03*
Y834920D03*
Y836890D03*
Y838860D03*
Y840825D03*
Y842795D03*
X352585Y1210360D03*
Y1208390D03*
Y1206420D03*
Y1204455D03*
Y1202485D03*
Y1200515D03*
Y1198545D03*
Y1196580D03*
Y1194610D03*
Y1192640D03*
Y1190675D03*
Y1188705D03*
X387415D03*
Y1190675D03*
Y1192640D03*
Y1194610D03*
Y1196580D03*
Y1198545D03*
Y1200515D03*
Y1202485D03*
Y1204455D03*
Y1206420D03*
Y1208390D03*
Y1210360D03*
X352585Y1214295D03*
Y1212325D03*
X387415D03*
Y1214295D03*
X352585Y1712795D03*
Y1710825D03*
Y1708860D03*
Y1706890D03*
Y1704920D03*
Y1702955D03*
Y1700985D03*
Y1699015D03*
Y1697045D03*
Y1695080D03*
Y1693110D03*
Y1691140D03*
Y1689175D03*
Y1687205D03*
X387415D03*
Y1689175D03*
Y1691140D03*
Y1693110D03*
Y1695080D03*
Y1697045D03*
Y1699015D03*
Y1700985D03*
Y1702955D03*
Y1704920D03*
Y1706890D03*
Y1708860D03*
Y1710825D03*
Y1712795D03*
G54D52*
X113957Y1488286D03*
Y1490846D03*
Y1493406D03*
Y1495966D03*
X181318Y547147D03*
Y544587D03*
Y542027D03*
Y539467D03*
X165138D03*
Y542027D03*
Y544587D03*
Y547147D03*
X130137Y1495966D03*
Y1493406D03*
Y1490846D03*
Y1488286D03*
X836830Y191633D03*
Y189073D03*
X820650D03*
Y191633D03*
X836830Y196753D03*
Y194193D03*
X820650D03*
Y196753D03*
X836830Y1810927D03*
Y1808367D03*
Y1805807D03*
Y1803247D03*
X820650D03*
Y1805807D03*
Y1808367D03*
Y1810927D03*
G54D61*
X300000Y585500D03*
Y1421500D03*
G54D34*
X63500Y245215D03*
X59625Y237715D03*
X67375D03*
X63500Y650727D03*
X59625Y643227D03*
X67375D03*
X67000Y1058250D03*
X63125Y1050750D03*
X70875D03*
X63500Y1461750D03*
X59625Y1454250D03*
X67375D03*
X101300Y1860650D03*
X97425Y1853150D03*
X105175D03*
X73100Y1867150D03*
X69225Y1859650D03*
X76975D03*
X136500Y156250D03*
X132625Y148750D03*
X140375D03*
X144525Y412850D03*
X152275D03*
X148400Y420350D03*
X121625Y556250D03*
X129375D03*
X125500Y563750D03*
X148400Y825850D03*
X144525Y818350D03*
X152275D03*
X151500Y971250D03*
X147625Y963750D03*
X155375D03*
X148700Y1231350D03*
X144825Y1223850D03*
X152575D03*
X140500Y1371785D03*
X136625Y1364285D03*
X144375D03*
X149900Y1636850D03*
X146025Y1629350D03*
X153775D03*
X197000Y46250D03*
X193125Y38750D03*
X200875D03*
X876161Y163411D03*
X880036Y155911D03*
X872286D03*
X869000Y547215D03*
X872875Y539715D03*
X865125D03*
X878375Y555715D03*
X870625D03*
X874500Y563215D03*
X869000Y952727D03*
X872875Y945227D03*
X865125D03*
X874500Y968727D03*
X878375Y961227D03*
X870625D03*
X869000Y1358238D03*
X872875Y1350738D03*
X865125D03*
X874500Y1374238D03*
X878375Y1366738D03*
X870625D03*
X869000Y1763750D03*
X865125Y1756250D03*
X872875D03*
X874500Y1779750D03*
X870625Y1772250D03*
X878375D03*
G54D26*
X33375Y1970275D03*
X85475Y377775D03*
Y783275D03*
X63495Y1012436D03*
X85475Y1188775D03*
X64140Y1417910D03*
X92800Y1497000D03*
Y1492000D03*
X109100Y1543700D03*
X84400Y1840600D03*
X94400Y1839900D03*
X84400Y1836300D03*
X84900Y1867400D03*
X144700Y426600D03*
X115800Y454500D03*
Y449500D03*
X167300Y556330D03*
X167295Y560416D03*
X144700Y832100D03*
X115800Y860000D03*
Y855000D03*
X166217Y960000D03*
X164830Y979729D03*
X145000Y1237600D03*
X115800Y1265500D03*
Y1260500D03*
X151259Y1352302D03*
Y1347802D03*
X146200Y1643100D03*
X115800Y1671000D03*
Y1666000D03*
X119000Y1943900D03*
X193300Y52500D03*
X190300Y135000D03*
X200300Y569000D03*
X191454Y1346488D03*
X324800Y408500D03*
Y404400D03*
Y421000D03*
Y417000D03*
Y425000D03*
X325800Y609000D03*
Y597000D03*
X276800Y573000D03*
Y565000D03*
Y585000D03*
Y577000D03*
Y597000D03*
Y589000D03*
X325800D03*
X324800Y838500D03*
Y847000D03*
Y834400D03*
Y851000D03*
Y855000D03*
Y1210000D03*
Y1205800D03*
Y1222500D03*
Y1218500D03*
Y1226500D03*
X276800Y1419500D03*
Y1411500D03*
Y1423500D03*
Y1403500D03*
Y1431500D03*
X324800Y1721000D03*
Y1708500D03*
Y1717000D03*
Y1704300D03*
X268800Y1722000D03*
X324800Y1725000D03*
X363800Y58000D03*
X330800Y377000D03*
X334800Y389000D03*
X330800Y381000D03*
Y385000D03*
X387300Y459000D03*
X351800D03*
X379300D03*
X343800D03*
X330800Y807000D03*
X402300Y820000D03*
Y805000D03*
Y824000D03*
Y809000D03*
X334800Y819000D03*
X330800Y815000D03*
Y811000D03*
X387300Y889000D03*
X351800D03*
X379300D03*
X343800D03*
X334800Y1190500D03*
X402300Y1207500D03*
Y1211500D03*
X330800Y1178500D03*
Y1182500D03*
Y1186500D03*
X387300Y1260500D03*
X351800D03*
X402300Y1222500D03*
Y1226500D03*
X379300Y1260500D03*
X343800D03*
X330800Y1677000D03*
X334800Y1691000D03*
X402300Y1721000D03*
Y1706000D03*
Y1710000D03*
X330800Y1681000D03*
Y1685000D03*
X351800Y1759000D03*
X402300Y1725000D03*
X343800Y1759000D03*
X760214Y1968282D03*
X799300Y193000D03*
Y198000D03*
X811975Y377775D03*
Y783275D03*
Y1188775D03*
Y1594275D03*
X799300Y1812000D03*
Y1807000D03*
X886300Y157000D03*
Y161000D03*
X895275Y154724D03*
X887116Y168354D03*
X861800Y553465D03*
X884550Y556715D03*
Y560715D03*
X893541Y560408D03*
X861800Y958977D03*
X884550Y962227D03*
Y966227D03*
X893774Y965913D03*
X861800Y1364488D03*
X883988Y1365200D03*
Y1369700D03*
X893385Y1371351D03*
X884550Y1773250D03*
X861800Y1770000D03*
X884550Y1777250D03*
X893700Y1776900D03*
X847900Y1945200D03*
X919800Y129953D03*
Y535465D03*
Y940977D03*
Y1346488D03*
X951300Y1668500D03*
Y1663500D03*
X915800Y1715000D03*
X919800Y1752000D03*
G54D17*
X29400Y1778850D03*
Y1775350D03*
X76587Y1854268D03*
X177200Y553500D03*
X124700Y1502000D03*
X357200Y120500D03*
Y117000D03*
X363700Y76500D03*
X387200Y447500D03*
X351700D03*
X379200D03*
X343700D03*
X387200Y877500D03*
X351700D03*
X379200D03*
X343700D03*
X387200Y1249000D03*
X351700D03*
X379200D03*
X343700D03*
X351700Y1747500D03*
X343700D03*
X831200Y203000D03*
Y1817000D03*
X911700Y1691000D03*
Y1699000D03*
X885700Y1698000D03*
G54D44*
X107750Y373900D03*
X100250Y377775D03*
Y370025D03*
Y775525D03*
X107750Y779400D03*
X100250Y783275D03*
X107750Y1184900D03*
X100250Y1188775D03*
Y1181025D03*
X109125Y1588650D03*
Y1580900D03*
X97125Y1584775D03*
X89625Y1588650D03*
Y1580900D03*
X74450Y1965200D03*
X66950Y1969075D03*
Y1961325D03*
X55350Y1965300D03*
X47850Y1969175D03*
Y1961425D03*
X127250Y373900D03*
X119750Y377775D03*
Y370025D03*
Y775525D03*
X127250Y779400D03*
X119750Y783275D03*
X127250Y1184900D03*
X119750Y1188775D03*
Y1181025D03*
X116625Y1584775D03*
X834250Y373900D03*
X826750Y370025D03*
Y377775D03*
Y775525D03*
X834250Y779400D03*
X826750Y783275D03*
X834250Y1184900D03*
X826750Y1181025D03*
Y1188775D03*
X834250Y1590400D03*
X826750Y1586525D03*
Y1594275D03*
X782489Y1964407D03*
X774989Y1960532D03*
Y1968282D03*
X801989Y1964407D03*
X794489Y1960532D03*
Y1968282D03*
X876750Y145000D03*
X869250Y141125D03*
Y148875D03*
X853750Y373900D03*
X846250Y370025D03*
Y377775D03*
Y775525D03*
X853750Y779400D03*
X846250Y783275D03*
X853750Y1184900D03*
X846250Y1181025D03*
Y1188775D03*
X853750Y1590400D03*
X846250Y1586525D03*
Y1594275D03*
G54D53*
X85640Y1847150D03*
X88200D03*
X90760D03*
Y1853650D03*
X85640D03*
X150940Y556750D03*
X153500D03*
X156060D03*
Y563250D03*
X150940D03*
X187440Y949750D03*
X190000D03*
X192560D03*
Y956250D03*
X187440D03*
G54D71*
X357205Y382585D03*
X359175D03*
X361140D03*
X363110D03*
X365080D03*
X367045D03*
X369015D03*
X370985D03*
X372955D03*
X374920D03*
X376890D03*
X378860D03*
X380825D03*
X382795D03*
Y417415D03*
X380825D03*
X378860D03*
X376890D03*
X374920D03*
X372955D03*
X370985D03*
X369015D03*
X367045D03*
X365080D03*
X363110D03*
X361140D03*
X359175D03*
X357205D03*
Y812585D03*
X359175D03*
X361140D03*
X363110D03*
X365080D03*
X367045D03*
X369015D03*
X370985D03*
X372955D03*
X374920D03*
X376890D03*
X378860D03*
X380825D03*
X382795D03*
Y847415D03*
X380825D03*
X378860D03*
X376890D03*
X374920D03*
X372955D03*
X370985D03*
X369015D03*
X367045D03*
X365080D03*
X363110D03*
X361140D03*
X359175D03*
X357205D03*
Y1184085D03*
X359175D03*
X361140D03*
X363110D03*
X365080D03*
X367045D03*
X369015D03*
X370985D03*
X372955D03*
X374920D03*
X376890D03*
X378860D03*
X380825D03*
X382795D03*
Y1218915D03*
X380825D03*
X378860D03*
X376890D03*
X374920D03*
X372955D03*
X370985D03*
X369015D03*
X367045D03*
X365080D03*
X363110D03*
X361140D03*
X359175D03*
X357205D03*
Y1682585D03*
X359175D03*
X361140D03*
X363110D03*
X365080D03*
X367045D03*
X369015D03*
X370985D03*
X372955D03*
X374920D03*
X376890D03*
X378860D03*
X380825D03*
X382795D03*
Y1717415D03*
X380825D03*
X378860D03*
X376890D03*
X374920D03*
X372955D03*
X370985D03*
X369015D03*
X367045D03*
X365080D03*
X363110D03*
X361140D03*
X359175D03*
X357205D03*
G54D62*
X304921Y1413400D03*
X295079D03*
Y1429600D03*
X304921D03*
X355235Y382083D03*
X384765D03*
Y417917D03*
X355235D03*
Y812083D03*
X384765D03*
Y847917D03*
X355235D03*
Y1183583D03*
X384765D03*
Y1219417D03*
X355235D03*
Y1682083D03*
X384765D03*
Y1717917D03*
X355235D03*
X896453Y1703894D03*
X890547D03*
Y1716106D03*
X896453D03*
G54D80*
X916500Y1723150D03*
G54D35*
X92800Y210000D03*
X77300Y253465D03*
X92800Y214465D03*
X78550Y239715D03*
X92800Y201000D03*
Y205500D03*
X96000Y349000D03*
X92800Y615500D03*
Y619977D03*
Y611000D03*
X77300Y658977D03*
X78550Y645227D03*
X96000Y754500D03*
X92800Y1021000D03*
X77300Y1064488D03*
X92800Y1025488D03*
Y1016500D03*
X96000Y1160400D03*
X92800Y1426500D03*
Y1417500D03*
Y1422000D03*
X77300Y1470000D03*
X92800Y1431000D03*
X95300Y1556500D03*
X109100Y1548200D03*
X93800Y1830000D03*
X101900Y1839900D03*
X93800Y1821500D03*
X68275Y1823331D03*
X70110Y1837270D03*
X93787Y1825915D03*
X65800Y1940500D03*
X177954Y147453D03*
X132675Y162475D03*
X167656Y168811D03*
X124800Y321000D03*
Y326000D03*
X154750Y397350D03*
X181800Y531000D03*
Y527000D03*
X124800Y726500D03*
Y731500D03*
X176800Y963500D03*
X157046Y976999D03*
X124800Y1132000D03*
Y1137000D03*
X155125Y1208725D03*
X177954Y1362488D03*
X136675Y1378010D03*
X167674Y1385323D03*
X124800Y1537500D03*
Y1542500D03*
X155125Y1614225D03*
X181646Y1774500D03*
X167492Y1790692D03*
X123100Y1934100D03*
Y1939100D03*
X205625Y23725D03*
X192300Y167000D03*
Y158000D03*
Y162500D03*
X191800Y573500D03*
X209300Y569000D03*
X191800Y564500D03*
Y569000D03*
X192300Y978500D03*
X203900Y960977D03*
X192300Y969500D03*
X203900Y965477D03*
X192300Y974000D03*
X186800Y1382000D03*
Y1373000D03*
Y1377500D03*
X191300Y1790500D03*
X216000Y1772100D03*
X244900Y1769900D03*
X191300Y1781500D03*
X216000Y1776200D03*
X191300Y1786000D03*
X324800Y413000D03*
X329300Y570580D03*
Y578600D03*
X325800Y605000D03*
Y593000D03*
X320300Y572500D03*
Y576500D03*
X325800Y601000D03*
X324800Y843000D03*
Y1214500D03*
X276800Y1407500D03*
X319800Y1429700D03*
Y1417500D03*
Y1425700D03*
Y1405400D03*
Y1413500D03*
Y1437700D03*
X324800Y1713000D03*
X276800Y1722000D03*
X363800Y68500D03*
X344800Y341000D03*
X380300D03*
X334800Y393000D03*
X330800Y373000D03*
X352800Y341000D03*
X388300D03*
X373800Y771000D03*
X381800D03*
X334800Y823000D03*
X330800Y803000D03*
X397300Y840500D03*
X380300Y1142500D03*
X330800Y1174500D03*
X334800Y1194500D03*
X398800Y1192000D03*
X388300Y1142500D03*
X344800Y1641000D03*
X352800D03*
X330800Y1673000D03*
X334800Y1695000D03*
X421300Y817500D03*
Y809500D03*
Y1212000D03*
Y1220000D03*
Y1718500D03*
Y1710500D03*
X824300Y349000D03*
Y754500D03*
Y1160000D03*
Y1565500D03*
X789139Y1939507D03*
X907300Y146453D03*
X852800Y321000D03*
Y326000D03*
X906300Y551965D03*
X895976Y574422D03*
X852800Y726500D03*
Y731500D03*
X906300Y957477D03*
X852800Y1132000D03*
Y1137000D03*
X906300Y1362988D03*
X852800Y1537500D03*
Y1542500D03*
X911800Y1695000D03*
Y1703000D03*
X906300Y1768500D03*
X895492Y1790816D03*
X851800Y1935800D03*
X847900Y1949700D03*
X851800Y1940800D03*
X919800Y164453D03*
Y155500D03*
Y160000D03*
Y569965D03*
Y561000D03*
Y565500D03*
Y975477D03*
Y966500D03*
Y971000D03*
Y1380988D03*
Y1372000D03*
Y1376500D03*
Y1786500D03*
Y1777500D03*
Y1782000D03*
G54D54*
X87200Y1960400D03*
Y1968000D03*
X129725Y1581125D03*
Y1588725D03*
X388000Y1728700D03*
Y1736300D03*
X835500Y1700200D03*
Y1707800D03*
X827500D03*
Y1700200D03*
X835500Y1734800D03*
Y1727200D03*
X827500D03*
Y1734800D03*
X815339Y1959407D03*
Y1967007D03*
X884500Y1730800D03*
Y1723200D03*
G54D45*
X105025Y401025D03*
X97425D03*
X105200Y805700D03*
X97600D03*
X105100Y1211800D03*
X97500D03*
X105000Y1616700D03*
X97400D03*
X160400Y36600D03*
X152800D03*
X139000Y375300D03*
X146600D03*
X139100Y780600D03*
X146700D03*
X137700Y1185900D03*
X145300D03*
X315200Y422600D03*
X307600D03*
X315500Y853100D03*
X307900D03*
X314800Y1224000D03*
X307200D03*
X315300Y1722100D03*
X307700D03*
X398700Y420500D03*
Y850500D03*
X400700Y1232500D03*
X406300Y420500D03*
Y850500D03*
X408300Y1232500D03*
X866800Y376400D03*
X874400D03*
X866300Y781900D03*
X873900D03*
X866300Y1187400D03*
X873900D03*
X866300Y1594400D03*
X873900D03*
G54D27*
X89764Y41771D03*
Y44921D03*
Y48070D03*
Y51220D03*
Y54370D03*
Y57519D03*
Y60669D03*
Y63818D03*
Y66968D03*
Y70118D03*
Y73267D03*
Y76417D03*
Y79567D03*
Y82716D03*
Y85866D03*
Y89015D03*
Y92165D03*
Y95315D03*
Y98464D03*
Y101614D03*
Y104763D03*
Y107913D03*
Y111063D03*
Y114212D03*
Y117362D03*
Y120511D03*
X77205Y115787D03*
Y118937D03*
X89764Y123661D03*
Y126811D03*
Y129960D03*
Y133110D03*
Y136259D03*
Y139409D03*
Y142559D03*
Y145708D03*
Y148858D03*
Y152007D03*
Y155157D03*
Y158307D03*
Y161456D03*
Y164606D03*
X77205Y122086D03*
Y125236D03*
Y128385D03*
Y131535D03*
X89764Y447283D03*
Y450433D03*
Y453582D03*
Y456732D03*
Y459882D03*
Y463031D03*
Y466181D03*
Y469330D03*
Y472480D03*
Y475630D03*
Y478779D03*
Y481929D03*
Y485079D03*
Y488228D03*
Y491378D03*
Y494527D03*
Y497677D03*
Y500827D03*
Y503976D03*
Y507126D03*
Y510275D03*
Y513425D03*
Y516575D03*
Y519724D03*
Y522874D03*
Y526023D03*
Y529173D03*
Y532323D03*
Y535472D03*
Y538622D03*
Y541771D03*
Y544921D03*
Y548071D03*
Y551220D03*
Y554370D03*
Y557519D03*
X77205Y521299D03*
Y524449D03*
Y527598D03*
Y530748D03*
Y533897D03*
Y537047D03*
X89764Y560669D03*
Y563819D03*
Y566968D03*
Y570118D03*
Y852795D03*
Y855945D03*
Y859094D03*
Y862244D03*
Y865394D03*
Y868543D03*
Y871693D03*
Y874842D03*
Y877992D03*
Y881142D03*
Y884291D03*
Y887441D03*
Y890591D03*
Y893740D03*
Y896890D03*
Y900039D03*
Y903189D03*
Y906339D03*
Y909488D03*
Y912638D03*
Y915787D03*
Y918937D03*
Y922087D03*
Y925236D03*
Y928386D03*
Y931535D03*
Y934685D03*
Y937835D03*
Y940984D03*
Y944134D03*
Y947283D03*
Y950433D03*
Y953583D03*
Y956732D03*
Y959882D03*
Y963031D03*
Y966181D03*
Y969331D03*
Y972480D03*
Y975630D03*
X77205Y926811D03*
Y929961D03*
Y933110D03*
Y936260D03*
Y939409D03*
Y942559D03*
X89764Y1258307D03*
Y1261457D03*
Y1264606D03*
Y1267756D03*
Y1270906D03*
Y1274055D03*
Y1277205D03*
Y1280354D03*
Y1283504D03*
Y1286654D03*
Y1289803D03*
Y1292953D03*
Y1296103D03*
Y1299252D03*
Y1302402D03*
Y1305551D03*
Y1308701D03*
Y1311851D03*
Y1315000D03*
Y1318150D03*
Y1321299D03*
Y1324449D03*
Y1327599D03*
Y1330748D03*
Y1333898D03*
Y1337047D03*
Y1340197D03*
Y1343347D03*
Y1346496D03*
Y1349646D03*
Y1352795D03*
Y1355945D03*
X77205Y1332323D03*
Y1335473D03*
Y1338622D03*
Y1341772D03*
Y1344921D03*
Y1348071D03*
X89764Y1359095D03*
Y1362244D03*
Y1365394D03*
Y1368543D03*
Y1371693D03*
Y1374843D03*
Y1377992D03*
Y1381142D03*
Y1663819D03*
Y1666969D03*
Y1670118D03*
Y1673268D03*
Y1676418D03*
Y1679567D03*
Y1682717D03*
Y1685866D03*
Y1689016D03*
Y1692166D03*
Y1695315D03*
Y1698465D03*
Y1701615D03*
Y1704764D03*
Y1707914D03*
Y1711063D03*
Y1714213D03*
Y1717363D03*
Y1720512D03*
Y1723662D03*
Y1726811D03*
Y1729961D03*
Y1733111D03*
Y1736260D03*
Y1739410D03*
Y1742559D03*
Y1745709D03*
Y1748859D03*
Y1752008D03*
Y1755158D03*
Y1758307D03*
Y1761457D03*
Y1764607D03*
Y1767756D03*
Y1770906D03*
Y1774055D03*
Y1777205D03*
Y1780355D03*
Y1783504D03*
Y1786654D03*
X77205Y1737835D03*
Y1740985D03*
Y1744134D03*
Y1747284D03*
Y1750433D03*
Y1753583D03*
X154331Y265315D03*
Y262165D03*
Y259015D03*
Y255866D03*
Y252716D03*
Y249567D03*
Y246417D03*
Y243267D03*
Y240118D03*
Y236968D03*
Y233819D03*
Y230669D03*
Y227519D03*
Y224370D03*
Y221220D03*
Y218071D03*
Y214921D03*
Y211771D03*
Y208622D03*
Y205472D03*
X166890Y254291D03*
Y251141D03*
Y247992D03*
Y244842D03*
Y241693D03*
Y238543D03*
X154331Y328307D03*
Y325157D03*
Y322008D03*
Y318858D03*
Y315708D03*
Y312559D03*
Y309409D03*
Y306260D03*
Y303110D03*
Y299960D03*
Y296811D03*
Y293661D03*
Y290511D03*
Y287362D03*
Y284212D03*
Y281063D03*
Y277913D03*
Y274763D03*
Y271614D03*
Y268464D03*
Y629882D03*
Y626732D03*
Y623583D03*
Y620433D03*
Y617283D03*
Y614134D03*
Y610984D03*
Y702323D03*
Y699173D03*
Y696023D03*
Y692874D03*
Y689724D03*
Y686575D03*
Y683425D03*
Y680275D03*
Y677126D03*
Y673976D03*
Y670827D03*
Y667677D03*
Y664527D03*
Y661378D03*
Y658228D03*
Y655079D03*
Y651929D03*
Y648779D03*
Y645630D03*
Y642480D03*
Y639331D03*
Y636181D03*
Y633031D03*
X166890Y659803D03*
Y656653D03*
Y653504D03*
Y650354D03*
Y647205D03*
Y644055D03*
X154331Y733819D03*
Y730669D03*
Y727520D03*
Y724370D03*
Y721220D03*
Y718071D03*
Y714921D03*
Y711772D03*
Y708622D03*
Y705472D03*
Y1063740D03*
Y1060591D03*
Y1057441D03*
Y1054291D03*
Y1051142D03*
Y1047992D03*
Y1044843D03*
Y1041693D03*
Y1038543D03*
Y1035394D03*
Y1032244D03*
Y1029095D03*
Y1025945D03*
Y1022795D03*
Y1019646D03*
Y1016496D03*
X166890Y1065315D03*
Y1062165D03*
Y1059016D03*
Y1055866D03*
Y1052717D03*
Y1049567D03*
X154331Y1139331D03*
Y1136181D03*
Y1133032D03*
Y1129882D03*
Y1126732D03*
Y1123583D03*
Y1120433D03*
Y1117284D03*
Y1114134D03*
Y1110984D03*
Y1107835D03*
Y1104685D03*
Y1101535D03*
Y1098386D03*
Y1095236D03*
Y1092087D03*
Y1088937D03*
Y1085787D03*
Y1082638D03*
Y1079488D03*
Y1076339D03*
Y1073189D03*
Y1070039D03*
Y1066890D03*
Y1428307D03*
Y1425158D03*
Y1422008D03*
Y1500748D03*
Y1497599D03*
Y1494449D03*
Y1491299D03*
Y1488150D03*
Y1485000D03*
Y1481851D03*
Y1478701D03*
Y1475551D03*
Y1472402D03*
Y1469252D03*
Y1466103D03*
Y1462953D03*
Y1459803D03*
Y1456654D03*
Y1453504D03*
Y1450355D03*
Y1447205D03*
Y1444055D03*
Y1440906D03*
Y1437756D03*
Y1434607D03*
Y1431457D03*
X166890Y1470827D03*
Y1467677D03*
Y1464528D03*
Y1461378D03*
Y1458229D03*
Y1455079D03*
X154331Y1544843D03*
Y1541693D03*
Y1538544D03*
Y1535394D03*
Y1532244D03*
Y1529095D03*
Y1525945D03*
Y1522796D03*
Y1519646D03*
Y1516496D03*
Y1513347D03*
Y1510197D03*
Y1507047D03*
Y1503898D03*
Y1865315D03*
Y1862166D03*
Y1859016D03*
Y1855867D03*
Y1852717D03*
Y1849567D03*
Y1846418D03*
Y1843268D03*
Y1840119D03*
Y1836969D03*
Y1833819D03*
Y1830670D03*
Y1827520D03*
X166890Y1866890D03*
Y1863741D03*
Y1860591D03*
X154331Y1937756D03*
Y1934607D03*
Y1931457D03*
Y1928308D03*
Y1925158D03*
Y1922008D03*
Y1918859D03*
Y1915709D03*
Y1912559D03*
Y1909410D03*
Y1906260D03*
Y1903111D03*
Y1899961D03*
Y1896811D03*
Y1893662D03*
Y1890512D03*
Y1887363D03*
Y1884213D03*
Y1881063D03*
Y1877914D03*
Y1874764D03*
Y1871615D03*
Y1868465D03*
X166890Y1876339D03*
Y1873189D03*
Y1870040D03*
X154331Y1950355D03*
Y1947205D03*
Y1944056D03*
Y1940906D03*
X882677Y265315D03*
Y262165D03*
Y259015D03*
Y255866D03*
Y252716D03*
Y249567D03*
Y246417D03*
Y243267D03*
Y240118D03*
Y236968D03*
Y233819D03*
Y230669D03*
Y227519D03*
Y224370D03*
Y221220D03*
Y218071D03*
Y214921D03*
Y211771D03*
Y208622D03*
Y205472D03*
X895236Y254291D03*
Y251141D03*
Y247992D03*
Y244842D03*
Y241693D03*
Y238543D03*
X882677Y328307D03*
Y325157D03*
Y322008D03*
Y318858D03*
Y315708D03*
Y312559D03*
Y309409D03*
Y306260D03*
Y303110D03*
Y299960D03*
Y296811D03*
Y293661D03*
Y290511D03*
Y287362D03*
Y284212D03*
Y281063D03*
Y277913D03*
Y274763D03*
Y271614D03*
Y268464D03*
Y629882D03*
Y626732D03*
Y623583D03*
Y620433D03*
Y617283D03*
Y614134D03*
Y610984D03*
Y702323D03*
Y699173D03*
Y696023D03*
Y692874D03*
Y689724D03*
Y686575D03*
Y683425D03*
Y680275D03*
Y677126D03*
Y673976D03*
Y670827D03*
Y667677D03*
Y664527D03*
Y661378D03*
Y658228D03*
Y655079D03*
Y651929D03*
Y648779D03*
Y645630D03*
Y642480D03*
Y639331D03*
Y636181D03*
Y633031D03*
X895236Y659803D03*
Y656653D03*
Y653504D03*
Y650354D03*
Y647205D03*
Y644055D03*
X882677Y733819D03*
Y730669D03*
Y727520D03*
Y724370D03*
Y721220D03*
Y718071D03*
Y714921D03*
Y711772D03*
Y708622D03*
Y705472D03*
Y1063740D03*
Y1060591D03*
Y1057441D03*
Y1054291D03*
Y1051142D03*
Y1047992D03*
Y1044843D03*
Y1041693D03*
Y1038543D03*
Y1035394D03*
Y1032244D03*
Y1029095D03*
Y1025945D03*
Y1022795D03*
Y1019646D03*
Y1016496D03*
X895236Y1065315D03*
Y1062165D03*
Y1059016D03*
Y1055866D03*
Y1052717D03*
Y1049567D03*
X882677Y1139331D03*
Y1136181D03*
Y1133032D03*
Y1129882D03*
Y1126732D03*
Y1123583D03*
Y1120433D03*
Y1117284D03*
Y1114134D03*
Y1110984D03*
Y1107835D03*
Y1104685D03*
Y1101535D03*
Y1098386D03*
Y1095236D03*
Y1092087D03*
Y1088937D03*
Y1085787D03*
Y1082638D03*
Y1079488D03*
Y1076339D03*
Y1073189D03*
Y1070039D03*
Y1066890D03*
Y1428307D03*
Y1425158D03*
Y1422008D03*
Y1500748D03*
Y1497599D03*
Y1494449D03*
Y1491299D03*
Y1488150D03*
Y1485000D03*
Y1481851D03*
Y1478701D03*
Y1475551D03*
Y1472402D03*
Y1469252D03*
Y1466103D03*
Y1462953D03*
Y1459803D03*
Y1456654D03*
Y1453504D03*
Y1450355D03*
Y1447205D03*
Y1444055D03*
Y1440906D03*
Y1437756D03*
Y1434607D03*
Y1431457D03*
X895236Y1470827D03*
Y1467677D03*
Y1464528D03*
Y1461378D03*
Y1458229D03*
Y1455079D03*
X882677Y1544843D03*
Y1541693D03*
Y1538544D03*
Y1535394D03*
Y1532244D03*
Y1529095D03*
Y1525945D03*
Y1522796D03*
Y1519646D03*
Y1516496D03*
Y1513347D03*
Y1510197D03*
Y1507047D03*
Y1503898D03*
Y1865315D03*
Y1862166D03*
Y1859016D03*
Y1855867D03*
Y1852717D03*
Y1849567D03*
Y1846418D03*
Y1843268D03*
Y1840119D03*
Y1836969D03*
Y1833819D03*
Y1830670D03*
Y1827520D03*
X895236Y1866890D03*
Y1863741D03*
Y1860591D03*
X882677Y1937756D03*
Y1934607D03*
Y1931457D03*
Y1928308D03*
Y1925158D03*
Y1922008D03*
Y1918859D03*
Y1915709D03*
Y1912559D03*
Y1909410D03*
Y1906260D03*
Y1903111D03*
Y1899961D03*
Y1896811D03*
Y1893662D03*
Y1890512D03*
Y1887363D03*
Y1884213D03*
Y1881063D03*
Y1877914D03*
Y1874764D03*
Y1871615D03*
Y1868465D03*
X895236Y1876339D03*
Y1873189D03*
Y1870040D03*
X882677Y1950355D03*
Y1947205D03*
Y1944056D03*
Y1940906D03*
G54D72*
X809000Y1723500D03*
X820000D03*
X809000Y1714500D03*
X820000D03*
X889853Y1660249D03*
X878853D03*
G54D63*
X291900Y1416579D03*
Y1426421D03*
X308100D03*
Y1416579D03*
X352083Y385235D03*
X387917D03*
X352083Y414765D03*
X387917D03*
X352083Y844765D03*
Y815235D03*
X387917D03*
Y844765D03*
X352083Y1186735D03*
X387917D03*
X352083Y1216265D03*
X387917D03*
X352083Y1714765D03*
Y1685235D03*
X387917D03*
Y1714765D03*
X887394Y1707047D03*
Y1712953D03*
X899606D03*
Y1707047D03*
G54D18*
X32600Y1823200D03*
Y1819700D03*
X151700Y569500D03*
X344700Y352500D03*
X380200D03*
X352700D03*
X388200D03*
X373700Y782500D03*
X381700D03*
X388200Y806500D03*
X380200Y1154000D03*
X388200D03*
X344700Y1652500D03*
X352700D03*
X385200Y1676500D03*
X386200Y1723500D03*
X914700Y1719000D03*
G54D36*
X96200Y210000D03*
X80700Y253465D03*
X96200Y214465D03*
X81950Y239715D03*
X96200Y201000D03*
Y205500D03*
X99400Y349000D03*
X96200Y615500D03*
Y619977D03*
Y611000D03*
X80700Y658977D03*
X81950Y645227D03*
X99400Y754500D03*
X96200Y1021000D03*
X80700Y1064488D03*
X96200Y1025488D03*
Y1016500D03*
X99400Y1160400D03*
X96200Y1426500D03*
Y1417500D03*
Y1422000D03*
X80700Y1470000D03*
X96200Y1431000D03*
X98700Y1556500D03*
X97200Y1830000D03*
X105300Y1839900D03*
X97200Y1821500D03*
X71675Y1823331D03*
X73510Y1837270D03*
X97187Y1825915D03*
X69200Y1940500D03*
X181354Y147453D03*
X136075Y162475D03*
X171056Y168811D03*
X128200Y321000D03*
Y326000D03*
X158150Y397350D03*
X128200Y726500D03*
Y731500D03*
X180200Y963500D03*
X160446Y976999D03*
X128200Y1132000D03*
Y1137000D03*
X158525Y1208725D03*
X181354Y1362488D03*
X140075Y1378010D03*
X171074Y1385323D03*
X128200Y1537500D03*
Y1542500D03*
X112500Y1548200D03*
X158525Y1614225D03*
X170892Y1790692D03*
X126500Y1934100D03*
Y1939100D03*
X209025Y23725D03*
X195700Y167000D03*
Y158000D03*
Y162500D03*
X185200Y531000D03*
Y527000D03*
X195200Y573500D03*
X212700Y569000D03*
X195200Y564500D03*
Y569000D03*
X195700Y978500D03*
X207300Y960977D03*
X195700Y969500D03*
X207300Y965477D03*
X195700Y974000D03*
X190200Y1382000D03*
Y1373000D03*
Y1377500D03*
X194700Y1790500D03*
X185046Y1774500D03*
X219400Y1772100D03*
X248300Y1769900D03*
X194700Y1781500D03*
X219400Y1776200D03*
X194700Y1786000D03*
X328200Y413000D03*
X329200Y605000D03*
Y593000D03*
X323700Y572500D03*
Y576500D03*
X329200Y601000D03*
X328200Y843000D03*
Y1214500D03*
X280200Y1407500D03*
X323200Y1429700D03*
Y1417500D03*
Y1425700D03*
Y1405400D03*
Y1413500D03*
Y1437700D03*
X328200Y1713000D03*
X280200Y1722000D03*
X367200Y68500D03*
X348200Y341000D03*
X383700D03*
X338200Y393000D03*
X334200Y373000D03*
X356200Y341000D03*
X391700D03*
X332700Y570580D03*
Y578600D03*
X377200Y771000D03*
X385200D03*
X338200Y823000D03*
X334200Y803000D03*
X400700Y840500D03*
X383700Y1142500D03*
X334200Y1174500D03*
X338200Y1194500D03*
X402200Y1192000D03*
X391700Y1142500D03*
X348200Y1641000D03*
X356200D03*
X334200Y1673000D03*
X338200Y1695000D03*
X424700Y817500D03*
Y809500D03*
Y1212000D03*
Y1220000D03*
Y1718500D03*
Y1710500D03*
X827700Y349000D03*
Y754500D03*
Y1160000D03*
Y1565500D03*
X792539Y1939507D03*
X910700Y146453D03*
X856200Y321000D03*
Y326000D03*
X909700Y551965D03*
X899376Y574422D03*
X856200Y726500D03*
Y731500D03*
X909700Y957477D03*
X856200Y1132000D03*
Y1137000D03*
X909700Y1362988D03*
X856200Y1537500D03*
Y1542500D03*
X909700Y1768500D03*
X898892Y1790816D03*
X855200Y1935800D03*
X851300Y1949700D03*
X855200Y1940800D03*
X923200Y164453D03*
Y155500D03*
Y160000D03*
Y569965D03*
Y561000D03*
Y565500D03*
Y975477D03*
Y966500D03*
Y971000D03*
Y1380988D03*
Y1372000D03*
Y1376500D03*
X915200Y1695000D03*
Y1703000D03*
X923200Y1786500D03*
Y1777500D03*
Y1782000D03*
G54D81*
X1009744Y1646102D03*
Y1641102D03*
Y1636102D03*
Y1631102D03*
Y1626102D03*
Y1621102D03*
Y1676102D03*
Y1671102D03*
Y1666102D03*
Y1661102D03*
Y1656102D03*
Y1651102D03*
G54D82*
G01X-106883Y-224955D02*
Y-304955D01*
G01Y-260455D02*
X1019417D01*
G01X-106883Y-304955D02*
X1019417D01*
G01X-110883Y-208955D02*
G02I-12000J0D01*
G01X-116033D02*
G02I-6850J0D01*
G01X-122883Y-224955D02*
Y-192955D01*
G01X-106883Y-208955D02*
X-138883D01*
G01X-106883Y-224955D02*
X1019417D01*
G01X231917D02*
Y-304955D01*
G01X369417Y-224955D02*
Y-304955D01*
G01X484417Y-224955D02*
Y-304955D01*
G01X651917Y-224955D02*
Y-304955D01*
G01X821917Y-224955D02*
Y-304955D01*
G01X1019417Y-224955D02*
Y-304955D01*
G01X1047417Y-208955D02*
G02I-12000J0D01*
G01X1042267D02*
G02I-6850J0D01*
G01X1035417Y-224955D02*
Y-192955D01*
G01X1051417Y-208955D02*
X1019417D01*
G54D55*
X308100Y416200D03*
Y846700D03*
X308200Y1217500D03*
X309200Y1715700D03*
X963700Y1661000D03*
Y1671000D03*
X919700Y1695000D03*
G54D37*
X59859Y204971D03*
X91200Y341300D03*
X94500Y369300D03*
X67414Y628262D03*
X91200Y746800D03*
X94500Y774800D03*
X77750Y1049436D03*
X91200Y1152700D03*
X94500Y1180300D03*
X76750Y1455150D03*
X90500Y1548800D03*
X83875Y1580175D03*
X77100Y1846200D03*
X61000Y1932800D03*
X56000Y1880800D03*
X41800Y1960600D03*
X180850Y27650D03*
X125700Y47900D03*
X146400Y136300D03*
X150557D03*
X114295Y331617D03*
X153625Y402425D03*
X129975Y401275D03*
X148400Y430900D03*
X120800Y441100D03*
X122025Y569675D03*
X117945Y737217D03*
X148400Y836400D03*
X154000Y808300D03*
X158500Y804300D03*
X130350Y807150D03*
X122251Y845546D03*
X178000Y952800D03*
X117900Y1142600D03*
X148700Y1241900D03*
X154000Y1213800D03*
X130350Y1212650D03*
X121500Y1252100D03*
X130000Y1473300D03*
X122000D03*
X114000D03*
X149900Y1647400D03*
X154000Y1619300D03*
X130350Y1619150D03*
X117000Y1657800D03*
X170080Y1773528D03*
X204500Y28800D03*
X197000Y56800D03*
X203000Y535300D03*
Y542800D03*
Y527800D03*
X194750Y1753050D03*
X200198Y1758800D03*
X305100Y393100D03*
X309300Y400600D03*
X313000Y562300D03*
X292000Y605300D03*
X284000D03*
X304000D03*
X296000D03*
X316000D03*
X308000D03*
X304500Y822600D03*
X308600Y830100D03*
X305200Y1194050D03*
X309300Y1201550D03*
X303500Y1392300D03*
X311500D03*
X287600Y1441300D03*
X279650D03*
X299600D03*
X291600D03*
X311600D03*
X303600D03*
X306200Y1692550D03*
X310300Y1700050D03*
X291500Y1788300D03*
X283500D03*
X275500D03*
X280500Y1731300D03*
X276500D03*
X272500D03*
X352500Y71800D03*
X378100Y84700D03*
X377500Y101300D03*
X344500Y364300D03*
X359500D03*
X340500D03*
X380000D03*
X395000D03*
X355500D03*
X376000D03*
X391000D03*
X398000Y406800D03*
X382500Y451300D03*
X347000D03*
X390500D03*
X355000D03*
X384500Y794300D03*
X388500D03*
X369500D03*
X373500D03*
X382500Y881300D03*
X347000D03*
X390500D03*
X355000D03*
X380000Y1165800D03*
X391000D03*
X395000D03*
X376000D03*
X382500Y1252800D03*
X347000D03*
X390500D03*
X355000D03*
X355500Y1664300D03*
X340500D03*
X359500D03*
X344500D03*
X379000Y1729300D03*
X347000Y1751300D03*
X355000D03*
X429000Y809300D03*
Y817300D03*
Y1211800D03*
Y1219800D03*
Y1710300D03*
Y1718300D03*
X836500Y174300D03*
X828500D03*
X820500D03*
X819500Y341300D03*
X821000Y369300D03*
X819500Y746800D03*
X821000Y774800D03*
X819500Y1152300D03*
X821000Y1180300D03*
X819500Y1557800D03*
X821000Y1585800D03*
X837500Y1788300D03*
X829500D03*
X819000D03*
X784339Y1931807D03*
X769239Y1959807D03*
X866961Y155961D03*
X844050Y330800D03*
X846200Y736800D03*
X844600Y1142200D03*
X845600Y1547800D03*
X906000Y1687800D03*
X859500Y1699300D03*
X902500Y1727300D03*
X898500D03*
X910500Y1727800D03*
X959000Y1668300D03*
G54D46*
X107200Y342500D03*
Y347500D03*
Y352500D03*
Y357500D03*
Y748000D03*
Y753000D03*
Y758000D03*
Y763000D03*
Y1153900D03*
Y1158900D03*
Y1163900D03*
Y1168900D03*
X106700Y1554100D03*
Y1559100D03*
Y1564100D03*
Y1569100D03*
X99500Y1939000D03*
Y1934000D03*
X79500D03*
Y1939000D03*
X99500Y1949000D03*
Y1944000D03*
X79500D03*
Y1949000D03*
X165500Y44000D03*
X185500D03*
X165500Y49000D03*
Y54000D03*
Y59000D03*
X185500D03*
Y54000D03*
Y49000D03*
X127200Y357500D03*
Y352500D03*
Y347500D03*
Y342500D03*
X116900Y418100D03*
Y423100D03*
Y428100D03*
Y433100D03*
X136900D03*
Y428100D03*
Y423100D03*
Y418100D03*
X127200Y763000D03*
Y758000D03*
Y753000D03*
Y748000D03*
X116900Y823600D03*
Y828600D03*
Y833600D03*
Y838600D03*
X136900D03*
Y833600D03*
Y828600D03*
Y823600D03*
X127200Y1168900D03*
Y1163900D03*
Y1158900D03*
Y1153900D03*
X117200Y1229100D03*
Y1234100D03*
Y1239100D03*
Y1244100D03*
X137200D03*
Y1239100D03*
Y1234100D03*
Y1229100D03*
X126700Y1569100D03*
Y1564100D03*
Y1559100D03*
Y1554100D03*
X118400Y1634600D03*
Y1639600D03*
Y1644600D03*
X138400D03*
Y1639600D03*
Y1634600D03*
X118400Y1649600D03*
X138400D03*
X835500Y357500D03*
Y352500D03*
Y347500D03*
Y342500D03*
Y763000D03*
Y758000D03*
Y753000D03*
Y748000D03*
Y1168500D03*
Y1163500D03*
Y1158500D03*
Y1153500D03*
Y1574000D03*
Y1569000D03*
Y1564000D03*
Y1559000D03*
X802439Y1939107D03*
Y1934107D03*
X822439D03*
Y1939107D03*
X802439Y1949107D03*
Y1944107D03*
X822439D03*
Y1949107D03*
X855500Y342500D03*
Y347500D03*
Y352500D03*
Y357500D03*
Y748000D03*
Y753000D03*
Y758000D03*
Y763000D03*
Y1153500D03*
Y1158500D03*
Y1163500D03*
Y1168500D03*
Y1559000D03*
Y1564000D03*
Y1569000D03*
Y1574000D03*
G54D28*
X78839Y41161D03*
Y46161D03*
Y51161D03*
Y56161D03*
Y61161D03*
Y66161D03*
Y71161D03*
Y76161D03*
Y81161D03*
Y86161D03*
Y91161D03*
Y96161D03*
Y101161D03*
Y106161D03*
Y111161D03*
Y136161D03*
Y141161D03*
Y146161D03*
Y151161D03*
Y156161D03*
Y161161D03*
Y166161D03*
Y446673D03*
Y451673D03*
Y456673D03*
Y461673D03*
Y466673D03*
Y471673D03*
Y476673D03*
Y481673D03*
Y486673D03*
Y491673D03*
Y496673D03*
Y501673D03*
Y506673D03*
Y511673D03*
Y516673D03*
Y541673D03*
Y546673D03*
Y551673D03*
Y556673D03*
Y561673D03*
Y566673D03*
Y571673D03*
Y852185D03*
Y857185D03*
Y862185D03*
Y867185D03*
Y872185D03*
Y877185D03*
Y882185D03*
Y887185D03*
Y892185D03*
Y897185D03*
Y902185D03*
Y907185D03*
Y912185D03*
Y917185D03*
Y922185D03*
Y947185D03*
Y952185D03*
Y957185D03*
Y962185D03*
Y967185D03*
Y972185D03*
Y977185D03*
Y1257697D03*
Y1262697D03*
Y1267697D03*
Y1272697D03*
Y1277697D03*
Y1282697D03*
Y1287697D03*
Y1292697D03*
Y1297697D03*
Y1302697D03*
Y1307697D03*
Y1312697D03*
Y1317697D03*
Y1322697D03*
Y1327697D03*
Y1352697D03*
Y1357697D03*
Y1362697D03*
Y1367697D03*
Y1372697D03*
Y1377697D03*
Y1382697D03*
Y1663209D03*
Y1668209D03*
Y1673209D03*
Y1678209D03*
Y1683209D03*
Y1688209D03*
Y1693209D03*
Y1698209D03*
Y1703209D03*
Y1708209D03*
Y1713209D03*
Y1718209D03*
Y1723209D03*
Y1728209D03*
Y1733209D03*
Y1758209D03*
Y1763209D03*
Y1768209D03*
Y1773209D03*
Y1778209D03*
Y1783209D03*
Y1788209D03*
X165256Y263917D03*
Y258917D03*
Y233917D03*
Y228917D03*
Y223917D03*
Y218917D03*
Y213917D03*
Y208917D03*
Y203917D03*
Y328917D03*
Y323917D03*
Y318917D03*
Y313917D03*
Y308917D03*
Y303917D03*
Y298917D03*
Y293917D03*
Y288917D03*
Y283917D03*
Y278917D03*
Y273917D03*
Y268917D03*
Y629429D03*
Y624429D03*
Y619429D03*
Y614429D03*
Y609429D03*
Y699429D03*
Y694429D03*
Y689429D03*
Y684429D03*
Y679429D03*
Y674429D03*
Y669429D03*
Y664429D03*
Y639429D03*
Y634429D03*
Y734429D03*
Y729429D03*
Y724429D03*
Y719429D03*
Y714429D03*
Y709429D03*
Y704429D03*
Y1044941D03*
Y1039941D03*
Y1034941D03*
Y1029941D03*
Y1024941D03*
Y1019941D03*
Y1014941D03*
Y1134941D03*
Y1129941D03*
Y1124941D03*
Y1119941D03*
Y1114941D03*
Y1109941D03*
Y1104941D03*
Y1099941D03*
Y1094941D03*
Y1089941D03*
Y1084941D03*
Y1079941D03*
Y1074941D03*
Y1069941D03*
Y1139941D03*
Y1430453D03*
Y1425453D03*
Y1420453D03*
Y1500453D03*
Y1495453D03*
Y1490453D03*
Y1485453D03*
Y1480453D03*
Y1475453D03*
Y1450453D03*
Y1445453D03*
Y1440453D03*
Y1435453D03*
Y1545453D03*
Y1540453D03*
Y1535453D03*
Y1530453D03*
Y1525453D03*
Y1520453D03*
Y1515453D03*
Y1510453D03*
Y1505453D03*
Y1855965D03*
Y1850965D03*
Y1845965D03*
Y1840965D03*
Y1835965D03*
Y1830965D03*
Y1825965D03*
Y1935965D03*
Y1930965D03*
Y1925965D03*
Y1920965D03*
Y1915965D03*
Y1910965D03*
Y1905965D03*
Y1900965D03*
Y1895965D03*
Y1890965D03*
Y1885965D03*
Y1880965D03*
Y1950965D03*
Y1945965D03*
Y1940965D03*
X893602Y263917D03*
Y258917D03*
Y233917D03*
Y228917D03*
Y223917D03*
Y218917D03*
Y213917D03*
Y208917D03*
Y203917D03*
Y328917D03*
Y323917D03*
Y318917D03*
Y313917D03*
Y308917D03*
Y303917D03*
Y298917D03*
Y293917D03*
Y288917D03*
Y283917D03*
Y278917D03*
Y273917D03*
Y268917D03*
Y629429D03*
Y624429D03*
Y619429D03*
Y614429D03*
Y609429D03*
Y699429D03*
Y694429D03*
Y689429D03*
Y684429D03*
Y679429D03*
Y674429D03*
Y669429D03*
Y664429D03*
Y639429D03*
Y634429D03*
Y734429D03*
Y729429D03*
Y724429D03*
Y719429D03*
Y714429D03*
Y709429D03*
Y704429D03*
Y1044941D03*
Y1039941D03*
Y1034941D03*
Y1029941D03*
Y1024941D03*
Y1019941D03*
Y1014941D03*
Y1134941D03*
Y1129941D03*
Y1124941D03*
Y1119941D03*
Y1114941D03*
Y1109941D03*
Y1104941D03*
Y1099941D03*
Y1094941D03*
Y1089941D03*
Y1084941D03*
Y1079941D03*
Y1074941D03*
Y1069941D03*
Y1139941D03*
Y1430453D03*
Y1425453D03*
Y1420453D03*
Y1500453D03*
Y1495453D03*
Y1490453D03*
Y1485453D03*
Y1480453D03*
Y1475453D03*
Y1450453D03*
Y1445453D03*
Y1440453D03*
Y1435453D03*
Y1545453D03*
Y1540453D03*
Y1535453D03*
Y1530453D03*
Y1525453D03*
Y1520453D03*
Y1515453D03*
Y1510453D03*
Y1505453D03*
Y1855965D03*
Y1850965D03*
Y1845965D03*
Y1840965D03*
Y1835965D03*
Y1830965D03*
Y1825965D03*
Y1935965D03*
Y1930965D03*
Y1925965D03*
Y1920965D03*
Y1915965D03*
Y1910965D03*
Y1905965D03*
Y1900965D03*
Y1895965D03*
Y1890965D03*
Y1885965D03*
Y1880965D03*
Y1950965D03*
Y1945965D03*
Y1940965D03*
G54D73*
X887444Y1709016D03*
Y1710984D03*
X899556D03*
Y1709016D03*
G54D64*
X302953Y1413700D03*
X300984D03*
X299016D03*
X297047D03*
Y1429300D03*
X299016D03*
X300984D03*
X302953D03*
G54D19*
X36200Y1823200D03*
Y1819700D03*
X155300Y569500D03*
X348300Y352500D03*
X383800D03*
X356300D03*
X391800D03*
X377300Y782500D03*
X385300D03*
X391800Y806500D03*
X383800Y1154000D03*
X391800D03*
X348300Y1652500D03*
X356300D03*
X388800Y1676500D03*
X389800Y1723500D03*
X918300Y1719000D03*
G54D83*
G01X-90900Y-277455D02*
Y-294955D01*
X-82166D01*
G01X-69033Y-283289D02*
Y-294955D01*
G01Y-278622D02*
X-69470Y-278330D01*
Y-277747D01*
X-69033Y-277455D01*
X-68596Y-277747D01*
Y-278330D01*
X-69033Y-278622D01*
G01X-54590Y-299330D02*
X-53061Y-300497D01*
X-51315Y-300788D01*
X-49787Y-300497D01*
X-48476Y-299039D01*
X-47603Y-296997D01*
Y-283289D01*
G01Y-285622D02*
X-48476Y-284455D01*
X-49787Y-283580D01*
X-51315Y-283289D01*
X-53061Y-283872D01*
X-54153Y-285038D01*
X-55027Y-287080D01*
X-55463Y-289122D01*
X-55245Y-290872D01*
X-54371Y-292914D01*
X-53061Y-294372D01*
X-51315Y-294955D01*
X-50005Y-294663D01*
X-48476Y-293497D01*
X-47603Y-292331D01*
G01X-37745Y-294955D02*
Y-277455D01*
G01Y-285913D02*
X-36653Y-284455D01*
X-35561Y-283580D01*
X-33815Y-283289D01*
X-32505Y-283580D01*
X-30976Y-284747D01*
X-30321Y-286497D01*
Y-294955D01*
G01X-16533Y-277455D02*
Y-294955D01*
G01X-19590Y-283289D02*
X-13476D01*
G01X-2745Y-294955D02*
Y-283289D01*
G01Y-286205D02*
X-1871Y-284747D01*
X-561Y-283580D01*
X1185Y-283289D01*
X2713Y-283580D01*
X4024Y-284747D01*
X4679Y-286788D01*
Y-294955D01*
G01X18467Y-283289D02*
Y-294955D01*
G01Y-278622D02*
X18030Y-278330D01*
Y-277747D01*
X18467Y-277455D01*
X18904Y-277747D01*
Y-278330D01*
X18467Y-278622D01*
G01X32255Y-294955D02*
Y-283289D01*
G01Y-286205D02*
X33129Y-284747D01*
X34439Y-283580D01*
X36185Y-283289D01*
X37713Y-283580D01*
X39024Y-284747D01*
X39679Y-286788D01*
Y-294955D01*
G01X50410Y-299330D02*
X51939Y-300497D01*
X53685Y-300788D01*
X55213Y-300497D01*
X56524Y-299039D01*
X57397Y-296997D01*
Y-283289D01*
G01Y-285622D02*
X56524Y-284455D01*
X55213Y-283580D01*
X53685Y-283289D01*
X51939Y-283872D01*
X50847Y-285038D01*
X49973Y-287080D01*
X49537Y-289122D01*
X49755Y-290872D01*
X50629Y-292914D01*
X51939Y-294372D01*
X53685Y-294955D01*
X54995Y-294663D01*
X56524Y-293497D01*
X57397Y-292331D01*
G01X84100Y-294955D02*
Y-277455D01*
X89340D01*
X91087Y-278330D01*
X92397Y-280372D01*
X92834Y-282705D01*
X92397Y-285038D01*
X91305Y-286788D01*
X89340Y-287664D01*
X84100D01*
G01X101164Y-294955D02*
Y-277455D01*
X105530D01*
X107277Y-278330D01*
X108587Y-279497D01*
X109679Y-281246D01*
X110552Y-283289D01*
X110770Y-286205D01*
X110552Y-289122D01*
X109679Y-291164D01*
X108587Y-292914D01*
X107277Y-294080D01*
X105530Y-294955D01*
X101164D01*
G01X119100D02*
Y-277455D01*
X124340D01*
X126087Y-278330D01*
X127397Y-280372D01*
X127834Y-282705D01*
X127397Y-285038D01*
X126305Y-286788D01*
X124340Y-287664D01*
X119100D01*
G01X142713Y-285622D02*
X143587Y-284747D01*
X144242Y-283289D01*
X144679Y-281246D01*
X144242Y-279497D01*
X143369Y-278330D01*
X141840Y-277455D01*
X135945D01*
Y-294955D01*
X143150D01*
X144679Y-293789D01*
X145552Y-292038D01*
X145989Y-289997D01*
X145552Y-287955D01*
X144242Y-286205D01*
X142713Y-285622D01*
X135945D01*
G01X171600Y-294955D02*
Y-277455D01*
X176840D01*
X178587Y-278330D01*
X179897Y-280372D01*
X180334Y-282705D01*
X179897Y-285038D01*
X178805Y-286788D01*
X176840Y-287664D01*
X171600D01*
G01X188008Y-277455D02*
X193467Y-294955D01*
X198926Y-277455D01*
G01X210967D02*
Y-294955D01*
G01X205945Y-277455D02*
X215989D01*
G01X21540Y-249955D02*
Y-232455D01*
X27217Y-247038D01*
X32894Y-232455D01*
Y-249955D01*
G01X44717D02*
X43407Y-249663D01*
X42097Y-248497D01*
X41223Y-246455D01*
X40787Y-244122D01*
X41223Y-241788D01*
X42097Y-239747D01*
X43407Y-238580D01*
X44717Y-238289D01*
X46027Y-238580D01*
X47337Y-239747D01*
X48210Y-241788D01*
X48429Y-244122D01*
X48210Y-246455D01*
X47337Y-248497D01*
X46027Y-249663D01*
X44717Y-249955D01*
G01X66147Y-232455D02*
Y-249955D01*
G01Y-247331D02*
X65274Y-248789D01*
X63963Y-249663D01*
X62435Y-249955D01*
X60689Y-249372D01*
X59379Y-247914D01*
X58505Y-246164D01*
X58287Y-244122D01*
X58505Y-242080D01*
X59379Y-240330D01*
X60689Y-238872D01*
X62435Y-238289D01*
X63963Y-238580D01*
X65055Y-239164D01*
X66147Y-240330D01*
G01X76442Y-242080D02*
X83429D01*
X82774Y-240038D01*
X81682Y-238872D01*
X80154Y-238289D01*
X78625Y-238580D01*
X77315Y-239455D01*
X76442Y-241497D01*
X76005Y-243247D01*
Y-244997D01*
X76442Y-246747D01*
X77534Y-248497D01*
X78844Y-249663D01*
X80372Y-249955D01*
X81900Y-249372D01*
X83429Y-247622D01*
G01X97217Y-249955D02*
Y-232455D01*
G01X252500Y-249955D02*
Y-232455D01*
X257740D01*
X259487Y-233330D01*
X260797Y-235372D01*
X261234Y-237705D01*
X260797Y-240038D01*
X259705Y-241788D01*
X257740Y-242664D01*
X252500D01*
G01X279170Y-233914D02*
X277860Y-233038D01*
X276332Y-232455D01*
X274585D01*
X272620Y-233330D01*
X271092Y-234788D01*
X270000Y-236539D01*
X269127Y-239455D01*
X268908Y-242080D01*
X269345Y-244705D01*
X270000Y-246455D01*
X271310Y-248205D01*
X272839Y-249372D01*
X274367Y-249955D01*
X275895D01*
X277424Y-249372D01*
X278734Y-248497D01*
X279826Y-247331D01*
G01X293613Y-240622D02*
X294487Y-239747D01*
X295142Y-238289D01*
X295579Y-236246D01*
X295142Y-234497D01*
X294269Y-233330D01*
X292740Y-232455D01*
X286845D01*
Y-249955D01*
X294050D01*
X295579Y-248789D01*
X296452Y-247038D01*
X296889Y-244997D01*
X296452Y-242955D01*
X295142Y-241205D01*
X293613Y-240622D01*
X286845D01*
G01X302817Y-255788D02*
X315917D01*
G01X321845Y-249955D02*
Y-232455D01*
X331889Y-249955D01*
Y-232455D01*
G01X344367Y-249955D02*
X342620Y-249663D01*
X341092Y-248497D01*
X339782Y-246747D01*
X338908Y-244705D01*
X338472Y-242372D01*
Y-240038D01*
X338908Y-237705D01*
X339782Y-235663D01*
X341092Y-233914D01*
X342620Y-232747D01*
X344367Y-232455D01*
X346113Y-232747D01*
X347642Y-233914D01*
X348952Y-235663D01*
X349826Y-237705D01*
X350262Y-240038D01*
Y-242372D01*
X349826Y-244705D01*
X348952Y-246747D01*
X347642Y-248497D01*
X346113Y-249663D01*
X344367Y-249955D01*
G01X265617Y-294955D02*
Y-277455D01*
X262997Y-280955D01*
G01Y-294955D02*
X268237D01*
G01X278314Y-292331D02*
X279623Y-293789D01*
X281152Y-294663D01*
X283117Y-294955D01*
X285082Y-294372D01*
X286610Y-293205D01*
X287702Y-291164D01*
X287920Y-288830D01*
X287484Y-286497D01*
X286392Y-285038D01*
X284863Y-283872D01*
X283335Y-283580D01*
X281807Y-283872D01*
X279842Y-285038D01*
X280497Y-277455D01*
X286392D01*
G01X296469Y-287664D02*
X297997Y-285622D01*
X299307Y-284455D01*
X301054Y-283872D01*
X302582Y-284455D01*
X303674Y-285622D01*
X304547Y-287372D01*
X304765Y-289413D01*
X304547Y-291164D01*
X303674Y-292914D01*
X302363Y-294372D01*
X300835Y-294955D01*
X299089Y-294372D01*
X297560Y-292622D01*
X296687Y-289997D01*
X296469Y-287080D01*
X296905Y-283289D01*
X297560Y-281246D01*
X298652Y-279205D01*
X300180Y-277747D01*
X301709Y-277455D01*
X303237Y-278038D01*
X304329Y-279497D01*
G01X313969Y-287664D02*
X315497Y-285622D01*
X316807Y-284455D01*
X318554Y-283872D01*
X320082Y-284455D01*
X321174Y-285622D01*
X322047Y-287372D01*
X322265Y-289413D01*
X322047Y-291164D01*
X321174Y-292914D01*
X319863Y-294372D01*
X318335Y-294955D01*
X316589Y-294372D01*
X315060Y-292622D01*
X314187Y-289997D01*
X313969Y-287080D01*
X314405Y-283289D01*
X315060Y-281246D01*
X316152Y-279205D01*
X317680Y-277747D01*
X319209Y-277455D01*
X320737Y-278038D01*
X321829Y-279497D01*
G01X331905Y-292914D02*
X333434Y-294372D01*
X335180Y-294955D01*
X336927Y-294372D01*
X338455Y-292622D01*
X339547Y-289997D01*
X339984Y-287372D01*
Y-284164D01*
X339547Y-281539D01*
X338455Y-279205D01*
X337145Y-278038D01*
X335617Y-277455D01*
X333870Y-278038D01*
X332560Y-279205D01*
X331687Y-280955D01*
X331250Y-283289D01*
X331687Y-285330D01*
X332779Y-287372D01*
X334089Y-288539D01*
X335617Y-288830D01*
X337363Y-288247D01*
X338674Y-286788D01*
X339984Y-284164D01*
G01X395208Y-232455D02*
X400667Y-249955D01*
X406126Y-232455D01*
G01X422534Y-249955D02*
X413800D01*
Y-232455D01*
X422534D01*
G01X419040Y-240913D02*
X413800D01*
G01X431300Y-249955D02*
Y-232455D01*
X436759D01*
X438505Y-233330D01*
X439597Y-234497D01*
X440034Y-236830D01*
X439597Y-239164D01*
X438287Y-240622D01*
X436759Y-241497D01*
X431300D01*
G01X436759D02*
X440034Y-249955D01*
G01X453167Y-250538D02*
X452730Y-250247D01*
Y-249663D01*
X453167Y-249372D01*
X453604Y-249663D01*
Y-250247D01*
X453167Y-250538D01*
G01X426917Y-294955D02*
Y-277455D01*
X424297Y-280955D01*
G01Y-294955D02*
X429537D01*
G01X528750Y-232455D02*
Y-249955D01*
X537484D01*
G01X554547D02*
Y-238289D01*
G01Y-240330D02*
X553674Y-239164D01*
X552363Y-238580D01*
X550835Y-238289D01*
X549307Y-238872D01*
X547997Y-240038D01*
X547123Y-241788D01*
X546687Y-244122D01*
X547123Y-246455D01*
X547997Y-248205D01*
X549307Y-249372D01*
X550835Y-249955D01*
X552363Y-249663D01*
X553674Y-248789D01*
X554547Y-247622D01*
G01X563532Y-255205D02*
X564842Y-255788D01*
X566589Y-255205D01*
X567680Y-254039D01*
X568554Y-252580D01*
X569863Y-247914D01*
X572702Y-238289D01*
G01X565715D02*
X569863Y-247914D01*
G01X582342Y-242080D02*
X589329D01*
X588674Y-240038D01*
X587582Y-238872D01*
X586054Y-238289D01*
X584525Y-238580D01*
X583215Y-239455D01*
X582342Y-241497D01*
X581905Y-243247D01*
Y-244997D01*
X582342Y-246747D01*
X583434Y-248497D01*
X584744Y-249663D01*
X586272Y-249955D01*
X587800Y-249372D01*
X589329Y-247622D01*
G01X600060Y-249955D02*
Y-238289D01*
G01Y-240622D02*
X601152Y-239455D01*
X602244Y-238580D01*
X603772Y-238289D01*
X604863Y-238580D01*
X606174Y-239455D01*
G01X541867Y-277455D02*
Y-294955D01*
G01X536845Y-277455D02*
X546889D01*
G01X554782Y-292622D02*
X556529Y-294080D01*
X558494Y-294955D01*
X560240D01*
X561987Y-294080D01*
X563297Y-292622D01*
X563952Y-290580D01*
X563515Y-288539D01*
X562424Y-286788D01*
X560459Y-285622D01*
X557839Y-285038D01*
X556310Y-283872D01*
X555655Y-281830D01*
X556092Y-279788D01*
X557184Y-278330D01*
X558712Y-277455D01*
X560240D01*
X561769Y-278038D01*
X563079Y-279497D01*
G01X571190Y-294955D02*
Y-277455D01*
X576867Y-292038D01*
X582544Y-277455D01*
Y-294955D01*
G01X589564D02*
Y-277455D01*
X593930D01*
X595677Y-278330D01*
X596987Y-279497D01*
X598079Y-281246D01*
X598952Y-283289D01*
X599170Y-286205D01*
X598952Y-289122D01*
X598079Y-291164D01*
X596987Y-292914D01*
X595677Y-294080D01*
X593930Y-294955D01*
X589564D01*
G01X670864Y-249955D02*
Y-232455D01*
X675230D01*
X676977Y-233330D01*
X678287Y-234497D01*
X679379Y-236246D01*
X680252Y-238289D01*
X680470Y-241205D01*
X680252Y-244122D01*
X679379Y-246164D01*
X678287Y-247914D01*
X676977Y-249080D01*
X675230Y-249955D01*
X670864D01*
G01X689892Y-242080D02*
X696879D01*
X696224Y-240038D01*
X695132Y-238872D01*
X693604Y-238289D01*
X692075Y-238580D01*
X690765Y-239455D01*
X689892Y-241497D01*
X689455Y-243247D01*
Y-244997D01*
X689892Y-246747D01*
X690984Y-248497D01*
X692294Y-249663D01*
X693822Y-249955D01*
X695350Y-249372D01*
X696879Y-247622D01*
G01X707392Y-247914D02*
X708484Y-249080D01*
X710012Y-249955D01*
X711322D01*
X712632Y-249372D01*
X713505Y-248497D01*
X713942Y-247331D01*
X713724Y-245580D01*
X712850Y-244705D01*
X708920Y-242955D01*
X708047Y-240913D01*
X708484Y-239455D01*
X709357Y-238580D01*
X710667Y-238289D01*
X711977Y-238580D01*
X713287Y-239455D01*
G01X728167Y-238289D02*
Y-249955D01*
G01Y-233622D02*
X727730Y-233330D01*
Y-232747D01*
X728167Y-232455D01*
X728604Y-232747D01*
Y-233330D01*
X728167Y-233622D01*
G01X742610Y-254330D02*
X744139Y-255497D01*
X745885Y-255788D01*
X747413Y-255497D01*
X748724Y-254039D01*
X749597Y-251997D01*
Y-238289D01*
G01Y-240622D02*
X748724Y-239455D01*
X747413Y-238580D01*
X745885Y-238289D01*
X744139Y-238872D01*
X743047Y-240038D01*
X742173Y-242080D01*
X741737Y-244122D01*
X741955Y-245872D01*
X742829Y-247914D01*
X744139Y-249372D01*
X745885Y-249955D01*
X747195Y-249663D01*
X748724Y-248497D01*
X749597Y-247331D01*
G01X759455Y-249955D02*
Y-238289D01*
G01Y-241205D02*
X760329Y-239747D01*
X761639Y-238580D01*
X763385Y-238289D01*
X764913Y-238580D01*
X766224Y-239747D01*
X766879Y-241788D01*
Y-249955D01*
G01X777392Y-242080D02*
X784379D01*
X783724Y-240038D01*
X782632Y-238872D01*
X781104Y-238289D01*
X779575Y-238580D01*
X778265Y-239455D01*
X777392Y-241497D01*
X776955Y-243247D01*
Y-244997D01*
X777392Y-246747D01*
X778484Y-248497D01*
X779794Y-249663D01*
X781322Y-249955D01*
X782850Y-249372D01*
X784379Y-247622D01*
G01X795110Y-249955D02*
Y-238289D01*
G01Y-240622D02*
X796202Y-239455D01*
X797294Y-238580D01*
X798822Y-238289D01*
X799913Y-238580D01*
X801224Y-239455D01*
G01X660367Y-277455D02*
X663423Y-294955D01*
X666917Y-277455D01*
X670410Y-294955D01*
X673467Y-277455D01*
G01X680050Y-294955D02*
Y-277455D01*
X685290D01*
X687037Y-278330D01*
X688347Y-280372D01*
X688784Y-282705D01*
X688347Y-285038D01*
X687255Y-286788D01*
X685290Y-287664D01*
X680050D01*
G01X697332Y-294955D02*
Y-277455D01*
G01X706502D02*
Y-294955D01*
G01Y-286205D02*
X697332D01*
G01X716579Y-289122D02*
X722255D01*
G01X732769Y-294955D02*
Y-277455D01*
X741065D01*
G01X738009Y-285913D02*
X732769D01*
G01X750050Y-277455D02*
Y-294955D01*
X758784D01*
G01X771917D02*
X770170Y-294663D01*
X768642Y-293497D01*
X767332Y-291747D01*
X766458Y-289705D01*
X766022Y-287372D01*
Y-285038D01*
X766458Y-282705D01*
X767332Y-280663D01*
X768642Y-278914D01*
X770170Y-277747D01*
X771917Y-277455D01*
X773663Y-277747D01*
X775192Y-278914D01*
X776502Y-280663D01*
X777376Y-282705D01*
X777812Y-285038D01*
Y-287372D01*
X777376Y-289705D01*
X776502Y-291747D01*
X775192Y-293497D01*
X773663Y-294663D01*
X771917Y-294955D01*
G01X785050D02*
Y-277455D01*
X790509D01*
X792255Y-278330D01*
X793347Y-279497D01*
X793784Y-281830D01*
X793347Y-284164D01*
X792037Y-285622D01*
X790509Y-286497D01*
X785050D01*
G01X790509D02*
X793784Y-294955D01*
G01X801458D02*
X806917Y-277455D01*
X812376Y-294955D01*
G01X810410Y-288830D02*
X803423D01*
G01X841867Y-294955D02*
Y-277455D01*
X839247Y-280955D01*
G01Y-294955D02*
X844487D01*
G01X859367D02*
Y-277455D01*
X856747Y-280955D01*
G01Y-294955D02*
X861987D01*
G01X872937Y-295538D02*
X880797Y-277455D01*
G01X894367Y-294955D02*
Y-277455D01*
X891747Y-280955D01*
G01Y-294955D02*
X896987D01*
G01X907719Y-287664D02*
X909247Y-285622D01*
X910557Y-284455D01*
X912304Y-283872D01*
X913832Y-284455D01*
X914924Y-285622D01*
X915797Y-287372D01*
X916015Y-289413D01*
X915797Y-291164D01*
X914924Y-292914D01*
X913613Y-294372D01*
X912085Y-294955D01*
X910339Y-294372D01*
X908810Y-292622D01*
X907937Y-289997D01*
X907719Y-287080D01*
X908155Y-283289D01*
X908810Y-281246D01*
X909902Y-279205D01*
X911430Y-277747D01*
X912959Y-277455D01*
X914487Y-278038D01*
X915579Y-279497D01*
G01X925437Y-295538D02*
X933297Y-277455D01*
G01X942719Y-280372D02*
X944029Y-278622D01*
X945557Y-277747D01*
X947304Y-277455D01*
X949487Y-278038D01*
X951015Y-279497D01*
X951452Y-281246D01*
X951234Y-282997D01*
X950360Y-284455D01*
X945994Y-287372D01*
X944029Y-289413D01*
X942719Y-292331D01*
X942282Y-294955D01*
X951452D01*
G01X964367Y-277455D02*
X962620Y-278038D01*
X961310Y-279497D01*
X960437Y-281246D01*
X959782Y-283580D01*
X959564Y-286205D01*
X959782Y-288830D01*
X960437Y-291164D01*
X961310Y-292914D01*
X962620Y-294372D01*
X964367Y-294955D01*
X966113Y-294372D01*
X967424Y-292914D01*
X968297Y-291164D01*
X968952Y-288830D01*
X969170Y-286205D01*
X968952Y-283580D01*
X968297Y-281246D01*
X967424Y-279497D01*
X966113Y-278038D01*
X964367Y-277455D01*
G01X981867Y-294955D02*
Y-277455D01*
X979247Y-280955D01*
G01Y-294955D02*
X984487D01*
G01X995219Y-287664D02*
X996747Y-285622D01*
X998057Y-284455D01*
X999804Y-283872D01*
X1001332Y-284455D01*
X1002424Y-285622D01*
X1003297Y-287372D01*
X1003515Y-289413D01*
X1003297Y-291164D01*
X1002424Y-292914D01*
X1001113Y-294372D01*
X999585Y-294955D01*
X997839Y-294372D01*
X996310Y-292622D01*
X995437Y-289997D01*
X995219Y-287080D01*
X995655Y-283289D01*
X996310Y-281246D01*
X997402Y-279205D01*
X998930Y-277747D01*
X1000459Y-277455D01*
X1001987Y-278038D01*
X1003079Y-279497D01*
G01X889564Y-249955D02*
Y-232455D01*
X893930D01*
X895677Y-233330D01*
X896987Y-234497D01*
X898079Y-236246D01*
X898952Y-238289D01*
X899170Y-241205D01*
X898952Y-244122D01*
X898079Y-246164D01*
X896987Y-247914D01*
X895677Y-249080D01*
X893930Y-249955D01*
X889564D01*
G01X915797D02*
Y-238289D01*
G01Y-240330D02*
X914924Y-239164D01*
X913613Y-238580D01*
X912085Y-238289D01*
X910557Y-238872D01*
X909247Y-240038D01*
X908373Y-241788D01*
X907937Y-244122D01*
X908373Y-246455D01*
X909247Y-248205D01*
X910557Y-249372D01*
X912085Y-249955D01*
X913613Y-249663D01*
X914924Y-248789D01*
X915797Y-247622D01*
G01X929367Y-232455D02*
Y-249955D01*
G01X926310Y-238289D02*
X932424D01*
G01X943592Y-242080D02*
X950579D01*
X949924Y-240038D01*
X948832Y-238872D01*
X947304Y-238289D01*
X945775Y-238580D01*
X944465Y-239455D01*
X943592Y-241497D01*
X943155Y-243247D01*
Y-244997D01*
X943592Y-246747D01*
X944684Y-248497D01*
X945994Y-249663D01*
X947522Y-249955D01*
X949050Y-249372D01*
X950579Y-247622D01*
G01X-7874Y0D02*
X-75552D01*
G02X-90552Y15000I0J15000D01*
G01Y519024D01*
G02X-75552Y534024I15000J0D01*
G01X-7874D01*
G01Y1030087D02*
X-75552D01*
G03X-90552Y1015087I0J-15000D01*
G01Y1001780D01*
G03X-75552Y986780I15000J0D01*
G01X-7874D01*
G01Y1992126D02*
X-75552D01*
G03X-90552Y1977126I0J-15000D01*
G01Y1915165D01*
G03X-75552Y1900165I15000J0D01*
G01X-7874D01*
G01X1023228Y1618051D02*
Y1675945D01*
G02X1028701Y1681417I5472J0D01*
G01X1033465D01*
X1037402Y1685354D01*
Y1988189D01*
G03X1033465Y1992126I-3937J0D01*
G01X3937D01*
G03X0Y1988189I0J-3937D01*
G01Y1661189D01*
X1969Y1659220D01*
X17323D01*
G02Y1650559I0J-4331D01*
G01X1969D01*
X0Y1648591D01*
Y1243866D01*
X1969Y1241898D01*
X17323D01*
G02Y1233236I0J-4331D01*
G01X1969D01*
X0Y1231268D01*
Y747803D01*
X1969Y745835D01*
X17323D01*
G02Y737173I0J-4331D01*
G01X1969D01*
X0Y735205D01*
Y3937D01*
G03X3937Y0I3937J0D01*
G01X121260D01*
X127310Y11888D01*
G03X127953Y14567I-5263J2680D01*
G01Y17717D01*
G02X139764I5906J0D01*
G01Y14567D01*
G03X140406Y11888I5906J-1D01*
G01X146457Y0D01*
X1033465D01*
G03X1037402Y3937I0J3937D01*
G01Y1424882D01*
X1033465Y1428819D01*
X1028701D01*
G02X1023228Y1434291I0J5473D01*
G01Y1609902D01*
X1021260Y1611870D01*
X993681D01*
G02Y1616083I0J2107D01*
G01X1021260D01*
X1023228Y1618051D01*
G01X-7874Y39059D02*
G03X0I3937J0D01*
G01Y8350D02*
G03X-7874I-3937J0D01*
G01D02*
Y0D01*
G01Y251657D02*
Y39059D01*
G01X0Y251657D02*
G03X-7874I-3937J0D01*
G01Y282366D02*
G03X0I3937J0D01*
G01X-7874Y494965D02*
Y282366D01*
G01Y525673D02*
G03X0I3937J0D01*
G01Y494965D02*
G03X-7874I-3937J0D01*
G01Y534024D02*
Y525673D01*
G01X0Y993079D02*
G03X-7874I-3937J0D01*
G01Y986780D02*
Y993079D01*
G01Y1023787D02*
G03X0I3937J0D01*
G01X-7874D02*
Y1030087D01*
G01Y1930791D02*
Y1900165D01*
G01X0Y1930791D02*
G03X-7874I-3937J0D01*
G01Y1961500D02*
G03X0I3937J0D01*
G01X-7874Y1992126D02*
Y1961500D01*
G01X1045276Y0D02*
X1112953D01*
G03X1127953Y15000I0J15000D01*
G01Y493259D01*
G01X1045276Y25827D02*
G03X1037402I-3937J0D01*
G01X1045276Y0D02*
Y25827D01*
G01X1037402Y56535D02*
G03X1045276I3937J0D01*
G01D02*
Y284882D01*
G01X1037402Y315591D02*
G03X1045276I3937J0D01*
G01Y284882D02*
G03X1037402I-3937J0D01*
G01X1045276Y315591D02*
Y543937D01*
G01D02*
G03X1037402I-3937J0D01*
G01Y574646D02*
G03X1045276I3937J0D01*
G01D02*
Y802992D01*
G01X1037402Y833701D02*
G03X1045276I3937J0D01*
G01Y802992D02*
G03X1037402I-3937J0D01*
G01X1045276Y833701D02*
Y1062047D01*
G01D02*
G03X1037402I-3937J0D01*
G01Y1092756D02*
G03X1045276I3937J0D01*
G01D02*
Y1321102D01*
G01D02*
G03X1037402I-3937J0D01*
G01Y1351811D02*
G03X1045276I3937J0D01*
G01D02*
Y1377638D01*
G01D02*
X1112953D01*
G02X1127953Y1362638I0J-15000D01*
G01Y501133D01*
G01X1045276Y1732598D02*
X1112953D01*
G03X1127953Y1747598I0J15000D01*
G01Y1977126D01*
G03X1112953Y1992126I-15000J0D01*
G01X1045276D01*
G01X1037402Y1767835D02*
G03X1045276I3937J0D01*
G01Y1737126D02*
G03X1037402I-3937J0D01*
G01X1045276Y1767835D02*
Y1956890D01*
G01Y1732598D02*
Y1737126D01*
G01X1037402Y1987598D02*
G03X1045276I3937J0D01*
G01Y1956890D02*
G03X1037402I-3937J0D01*
G01X1045276Y1987598D02*
Y1992126D01*
G01X1127953Y501133D02*
G03Y493259I0J-3937D01*
G54D38*
X59859Y208371D03*
X91200Y344700D03*
X94500Y372700D03*
X67414Y631662D03*
X91200Y750200D03*
X94500Y778200D03*
X77750Y1052836D03*
X91200Y1156100D03*
X94500Y1183700D03*
X76750Y1458550D03*
X90500Y1552200D03*
X83875Y1583575D03*
X77100Y1849600D03*
X61000Y1936200D03*
X56000Y1884200D03*
X41800Y1964000D03*
X180850Y31050D03*
X125700Y51300D03*
X146400Y139700D03*
X150557D03*
X114295Y335017D03*
X153625Y405825D03*
X129975Y404675D03*
X148400Y434300D03*
X120800Y444500D03*
X122025Y573075D03*
X117945Y740617D03*
X148400Y839800D03*
X154000Y811700D03*
X158500Y807700D03*
X130350Y810550D03*
X122251Y848946D03*
X178000Y956200D03*
X117900Y1146000D03*
X148700Y1245300D03*
X154000Y1217200D03*
X130350Y1216050D03*
X121500Y1255500D03*
X130000Y1476700D03*
X122000D03*
X114000D03*
X154000Y1622700D03*
X130350Y1622550D03*
X149900Y1650800D03*
X117000Y1661200D03*
X170080Y1776928D03*
X204500Y32200D03*
X197000Y60200D03*
X203000Y538700D03*
Y546200D03*
Y531200D03*
X194750Y1756450D03*
X200198Y1762200D03*
X305100Y396500D03*
X309300Y404000D03*
X313000Y565700D03*
X292000Y608700D03*
X284000D03*
X304000D03*
X296000D03*
X316000D03*
X308000D03*
X304500Y826000D03*
X308600Y833500D03*
X305200Y1197450D03*
X309300Y1204950D03*
X303500Y1395700D03*
X311500D03*
X287600Y1444700D03*
X279650D03*
X299600D03*
X291600D03*
X311600D03*
X303600D03*
X306200Y1695950D03*
X310300Y1703450D03*
X291500Y1791700D03*
X283500D03*
X275500D03*
X280500Y1734700D03*
X276500D03*
X272500D03*
X352500Y75200D03*
X378100Y88100D03*
X377500Y104700D03*
X344500Y367700D03*
X359500D03*
X340500D03*
X380000D03*
X395000D03*
X355500D03*
X376000D03*
X391000D03*
X398000Y410200D03*
X382500Y454700D03*
X347000D03*
X390500D03*
X355000D03*
X384500Y797700D03*
X388500D03*
X369500D03*
X373500D03*
X382500Y884700D03*
X347000D03*
X390500D03*
X355000D03*
X380000Y1169200D03*
X391000D03*
X395000D03*
X376000D03*
X382500Y1256200D03*
X347000D03*
X390500D03*
X355000D03*
X355500Y1667700D03*
X340500D03*
X359500D03*
X344500D03*
X379000Y1732700D03*
X347000Y1754700D03*
X355000D03*
X429000Y812700D03*
Y820700D03*
Y1215200D03*
Y1223200D03*
Y1713700D03*
Y1721700D03*
X836500Y177700D03*
X828500D03*
X820500D03*
X819500Y344700D03*
X821000Y372700D03*
X819500Y750200D03*
X821000Y778200D03*
X819500Y1155700D03*
X821000Y1183700D03*
X819500Y1561200D03*
X821000Y1589200D03*
X837500Y1791700D03*
X829500D03*
X819000D03*
X784339Y1935207D03*
X769239Y1963207D03*
X866961Y159361D03*
X844050Y334200D03*
X846200Y740200D03*
X844600Y1145600D03*
X845600Y1551200D03*
X906000Y1691200D03*
X859500Y1702700D03*
X902500Y1730700D03*
X898500D03*
X910500Y1731200D03*
X959000Y1671700D03*
G54D74*
X894484Y1716056D03*
X892516D03*
Y1703944D03*
X894484D03*
G54D65*
X292200Y1418547D03*
Y1420516D03*
Y1422484D03*
Y1424453D03*
X307800D03*
Y1422484D03*
Y1420516D03*
Y1418547D03*
G54D47*
X86050Y407200D03*
X67550D03*
X88650Y813200D03*
X70150D03*
X86650Y1218700D03*
X68150D03*
X84950Y1624000D03*
X66450D03*
X160350Y368300D03*
X178850D03*
X160550Y775400D03*
X179050D03*
X160050Y1179500D03*
X178550D03*
X161150Y1585700D03*
X179650D03*
X124950Y1965200D03*
X143450D03*
X889750Y368600D03*
X908250D03*
X889450Y774600D03*
X907950D03*
X893550Y1180600D03*
X912050D03*
X892050Y1584600D03*
X910550D03*
X853250Y1965500D03*
X871750D03*
G54D29*
X105400Y42350D03*
Y23850D03*
G54D56*
X313700Y416200D03*
Y846700D03*
X313800Y1217500D03*
X314800Y1715700D03*
X969300Y1661000D03*
Y1671000D03*
X925300Y1695000D03*
G54D48*
X99600Y411016D03*
Y421984D03*
X106300Y441484D03*
Y430516D03*
X100200Y816216D03*
Y827184D03*
X106300Y846584D03*
Y835616D03*
X106400Y1221916D03*
Y1232884D03*
Y1252284D03*
Y1241316D03*
X107000Y1647016D03*
X100000Y1627416D03*
Y1638384D03*
X107000Y1657984D03*
X109900Y1968184D03*
Y1957216D03*
X97400Y1968184D03*
Y1957216D03*
X139600Y48316D03*
X152100D03*
X139600Y59284D03*
X152100D03*
X137800Y334416D03*
X137900Y365084D03*
Y354116D03*
X137800Y345384D03*
X137900Y770684D03*
Y759716D03*
X137800Y740116D03*
Y751084D03*
X140000Y1175484D03*
Y1164516D03*
X137800Y1145116D03*
Y1156084D03*
X145500Y1571016D03*
X137600Y1550816D03*
Y1561784D03*
X145500Y1581984D03*
X838000Y1967984D03*
Y1957016D03*
X825500Y1967984D03*
Y1957016D03*
X866300Y335016D03*
X874000Y365484D03*
Y354516D03*
X866300Y345984D03*
X874000Y770984D03*
Y760016D03*
X866100Y740316D03*
Y751284D03*
X866000Y1176484D03*
Y1165516D03*
X866200Y1146016D03*
Y1156984D03*
X874500Y1572016D03*
X866300Y1552216D03*
Y1563184D03*
X874500Y1582984D03*
X973200Y1414216D03*
Y1425184D03*
X960700Y1414216D03*
Y1425184D03*
G54D39*
X97731Y241863D03*
Y244423D03*
Y246983D03*
X91231D03*
Y241863D03*
X97731Y647375D03*
Y649935D03*
Y652495D03*
X91231D03*
Y647375D03*
X97731Y1052886D03*
Y1055446D03*
Y1058006D03*
X91231D03*
Y1052886D03*
X97731Y1458398D03*
Y1460958D03*
Y1463518D03*
X91231D03*
Y1458398D03*
X162904Y141013D03*
Y138453D03*
Y135893D03*
X169404D03*
Y141013D03*
X162904Y1356548D03*
Y1353988D03*
Y1351428D03*
X169404D03*
Y1356548D03*
X207596Y1769440D03*
Y1772000D03*
Y1774560D03*
X201096D03*
Y1769440D03*
X898750Y140013D03*
Y134893D03*
X892250D03*
Y137453D03*
Y140013D03*
X897750Y545525D03*
Y540405D03*
X891250D03*
Y542965D03*
Y545525D03*
X897750Y951037D03*
Y945917D03*
X891250D03*
Y948477D03*
Y951037D03*
X897750Y1356548D03*
Y1351428D03*
X891250D03*
Y1353988D03*
Y1356548D03*
Y1762060D03*
Y1759500D03*
Y1756940D03*
X897750D03*
Y1762060D03*
G54D66*
X328600Y1696950D03*
Y1699150D03*
X337800Y397500D03*
Y399700D03*
X336800Y826950D03*
Y829150D03*
X337500Y1198450D03*
Y1200650D03*
G54D57*
X308100Y590421D03*
Y580579D03*
X291900D03*
Y590421D03*
G54D75*
X893500Y1710000D03*
G54D58*
X304921Y577400D03*
X295079D03*
Y593600D03*
X304921D03*
G54D67*
X280840Y1752400D03*
X278280D03*
X275720D03*
X273160D03*
Y1774600D03*
X275720D03*
X278280D03*
X280840D03*
G54D76*
X846557Y1720000D03*
X868443D03*
G54D49*
X84700Y357000D03*
Y348000D03*
Y762500D03*
Y753500D03*
Y1168400D03*
Y1159400D03*
X84000Y1564500D03*
Y1555500D03*
X54500Y1939500D03*
Y1948500D03*
X159400Y418600D03*
Y427600D03*
Y824100D03*
Y833100D03*
X159700Y1229600D03*
Y1238600D03*
X160900Y1635100D03*
Y1644100D03*
X208000Y44500D03*
Y53500D03*
X813000Y357000D03*
Y348000D03*
Y762500D03*
Y753500D03*
Y1168000D03*
Y1159000D03*
Y1573500D03*
Y1564500D03*
X777839Y1938507D03*
Y1947507D03*
G54D77*
X894500Y1730800D03*
Y1727200D03*
G54D59*
X307800Y588453D03*
Y586484D03*
Y584516D03*
Y582547D03*
X292200D03*
Y584516D03*
Y586484D03*
Y588453D03*
G54D68*
X354565Y104650D03*
X356530D03*
X358500D03*
X360470D03*
X362435D03*
Y88350D03*
X360470D03*
X358500D03*
X356530D03*
X354565D03*
G54D69*
X370000Y400000D03*
Y830000D03*
Y1201500D03*
Y1700000D03*
G54D78*
X983800Y1414300D03*
Y1425300D03*
G54D79*
X916500Y1725850D03*
M02*
